(kicad_sch
	(version 20250114)
	(generator "eeschema")
	(generator_version "9.0")
	(paper "A3")
	(title_block
		(title "CM4 Baseboard")
		(date "2026-01-05")
		(rev "1.1.1")
		(company "Antmicro Ltd")
		(comment 1 "www.antmicro.com")
	)
	(bus_alias "DSICtrl"
		(members "EN" "IRQ1" "DIM" "~{IRQ2}" "~{RST}" "GPIO")
	)
	(text "HDMI Connector"
		(exclude_from_sim no)
		(at 181.61 27.94 0)
		(effects
			(font
				(size 5.08 5.08)
				(thickness 1.016)
				(bold yes)
			)
			(justify left bottom)
		)
	)
	(text "Antmicro CM4 Baseboard \nDSI Connector"
		(exclude_from_sim no)
		(at 176.53 152.4 0)
		(effects
			(font
				(size 5.08 5.08)
				(thickness 1.016)
				(bold yes)
			)
			(justify left bottom)
		)
	)
	(junction
		(at 220.98 198.12)
		(diameter 0)
		(color 0 0 0 0)
	)
	(junction
		(at 124.46 208.28)
		(diameter 0)
		(color 0 0 0 0)
	)
	(junction
		(at 234.95 198.12)
		(diameter 0)
		(color 0 0 0 0)
	)
	(junction
		(at 124.46 205.74)
		(diameter 0)
		(color 0 0 0 0)
	)
	(junction
		(at 287.02 86.36)
		(diameter 0)
		(color 0 0 0 0)
	)
	(junction
		(at 287.02 81.28)
		(diameter 0)
		(color 0 0 0 0)
	)
	(junction
		(at 220.98 213.36)
		(diameter 0)
		(color 0 0 0 0)
	)
	(junction
		(at 236.22 185.42)
		(diameter 0)
		(color 0 0 0 0)
	)
	(junction
		(at 236.22 190.5)
		(diameter 0)
		(color 0 0 0 0)
	)
	(junction
		(at 255.27 91.44)
		(diameter 0)
		(color 0 0 0 0)
	)
	(junction
		(at 287.02 88.9)
		(diameter 0)
		(color 0 0 0 0)
	)
	(junction
		(at 245.11 91.44)
		(diameter 0)
		(color 0 0 0 0)
	)
	(junction
		(at 220.98 220.98)
		(diameter 0)
		(color 0 0 0 0)
	)
	(junction
		(at 220.98 205.74)
		(diameter 0)
		(color 0 0 0 0)
	)
	(junction
		(at 252.73 91.44)
		(diameter 0)
		(color 0 0 0 0)
	)
	(junction
		(at 259.08 172.72)
		(diameter 0)
		(color 0 0 0 0)
	)
	(junction
		(at 238.76 172.72)
		(diameter 0)
		(color 0 0 0 0)
	)
	(junction
		(at 220.98 190.5)
		(diameter 0)
		(color 0 0 0 0)
	)
	(junction
		(at 236.22 187.96)
		(diameter 0)
		(color 0 0 0 0)
	)
	(junction
		(at 287.02 83.82)
		(diameter 0)
		(color 0 0 0 0)
	)
	(junction
		(at 234.95 233.68)
		(diameter 0)
		(color 0 0 0 0)
	)
	(junction
		(at 287.02 91.44)
		(diameter 0)
		(color 0 0 0 0)
	)
	(junction
		(at 234.95 220.98)
		(diameter 0)
		(color 0 0 0 0)
	)
	(no_connect
		(at 222.25 223.52)
	)
	(no_connect
		(at 222.25 231.14)
	)
	(no_connect
		(at 233.68 223.52)
	)
	(no_connect
		(at 233.68 226.06)
	)
	(no_connect
		(at 233.68 228.6)
	)
	(no_connect
		(at 260.35 86.36)
	)
	(no_connect
		(at 233.68 231.14)
	)
	(no_connect
		(at 222.25 228.6)
	)
	(no_connect
		(at 222.25 226.06)
	)
	(bus_entry
		(at 227.33 55.88)
		(size 2.54 2.54)
		(stroke
			(width 0)
			(type default)
		)
	)
	(bus_entry
		(at 270.51 215.9)
		(size -2.54 2.54)
		(stroke
			(width 0)
			(type default)
		)
	)
	(bus_entry
		(at 207.01 182.88)
		(size 2.54 2.54)
		(stroke
			(width 0)
			(type default)
		)
	)
	(bus_entry
		(at 270.51 200.66)
		(size -2.54 2.54)
		(stroke
			(width 0)
			(type default)
		)
	)
	(bus_entry
		(at 207.01 200.66)
		(size 2.54 2.54)
		(stroke
			(width 0)
			(type default)
		)
	)
	(bus_entry
		(at 227.33 78.74)
		(size 2.54 2.54)
		(stroke
			(width 0)
			(type default)
		)
	)
	(bus_entry
		(at 140.97 195.58)
		(size -2.54 2.54)
		(stroke
			(width 0)
			(type default)
		)
	)
	(bus_entry
		(at 207.01 190.5)
		(size 2.54 2.54)
		(stroke
			(width 0)
			(type default)
		)
	)
	(bus_entry
		(at 158.75 40.64)
		(size 2.54 2.54)
		(stroke
			(width 0)
			(type default)
		)
	)
	(bus_entry
		(at 207.01 213.36)
		(size 2.54 2.54)
		(stroke
			(width 0)
			(type default)
		)
	)
	(bus_entry
		(at 158.75 63.5)
		(size 2.54 2.54)
		(stroke
			(width 0)
			(type default)
		)
	)
	(bus_entry
		(at 140.97 222.25)
		(size -2.54 2.54)
		(stroke
			(width 0)
			(type default)
		)
	)
	(bus_entry
		(at 140.97 162.56)
		(size -2.54 2.54)
		(stroke
			(width 0)
			(type default)
		)
	)
	(bus_entry
		(at 270.51 198.12)
		(size -2.54 2.54)
		(stroke
			(width 0)
			(type default)
		)
	)
	(bus_entry
		(at 270.51 200.66)
		(size -2.54 2.54)
		(stroke
			(width 0)
			(type default)
		)
	)
	(bus_entry
		(at 140.97 219.71)
		(size -2.54 2.54)
		(stroke
			(width 0)
			(type default)
		)
	)
	(bus_entry
		(at 207.01 205.74)
		(size 2.54 2.54)
		(stroke
			(width 0)
			(type default)
		)
	)
	(bus_entry
		(at 270.51 210.82)
		(size -2.54 2.54)
		(stroke
			(width 0)
			(type default)
		)
	)
	(bus_entry
		(at 227.33 40.64)
		(size 2.54 2.54)
		(stroke
			(width 0)
			(type default)
		)
	)
	(bus_entry
		(at 140.97 165.1)
		(size -2.54 2.54)
		(stroke
			(width 0)
			(type default)
		)
	)
	(bus_entry
		(at 207.01 198.12)
		(size 2.54 2.54)
		(stroke
			(width 0)
			(type default)
		)
	)
	(bus_entry
		(at 140.97 246.38)
		(size -2.54 2.54)
		(stroke
			(width 0)
			(type default)
		)
	)
	(bus_entry
		(at 227.33 76.2)
		(size 2.54 2.54)
		(stroke
			(width 0)
			(type default)
		)
	)
	(bus_entry
		(at 158.75 45.72)
		(size 2.54 2.54)
		(stroke
			(width 0)
			(type default)
		)
	)
	(bus_entry
		(at 140.97 241.3)
		(size -2.54 2.54)
		(stroke
			(width 0)
			(type default)
		)
	)
	(bus_entry
		(at 270.51 198.12)
		(size -2.54 2.54)
		(stroke
			(width 0)
			(type default)
		)
	)
	(bus_entry
		(at 158.75 60.96)
		(size 2.54 2.54)
		(stroke
			(width 0)
			(type default)
		)
	)
	(bus_entry
		(at 140.97 238.76)
		(size -2.54 2.54)
		(stroke
			(width 0)
			(type default)
		)
	)
	(bus_entry
		(at 140.97 179.07)
		(size -2.54 2.54)
		(stroke
			(width 0)
			(type default)
		)
	)
	(bus_entry
		(at 227.33 73.66)
		(size 2.54 2.54)
		(stroke
			(width 0)
			(type default)
		)
	)
	(bus_entry
		(at 227.33 38.1)
		(size 2.54 2.54)
		(stroke
			(width 0)
			(type default)
		)
	)
	(bus_entry
		(at 140.97 224.79)
		(size -2.54 2.54)
		(stroke
			(width 0)
			(type default)
		)
	)
	(bus_entry
		(at 270.51 205.74)
		(size -2.54 2.54)
		(stroke
			(width 0)
			(type default)
		)
	)
	(bus_entry
		(at 158.75 55.88)
		(size 2.54 2.54)
		(stroke
			(width 0)
			(type default)
		)
	)
	(bus_entry
		(at 158.75 58.42)
		(size 2.54 2.54)
		(stroke
			(width 0)
			(type default)
		)
	)
	(bus_entry
		(at 140.97 227.33)
		(size -2.54 2.54)
		(stroke
			(width 0)
			(type default)
		)
	)
	(bus_entry
		(at 140.97 157.48)
		(size -2.54 2.54)
		(stroke
			(width 0)
			(type default)
		)
	)
	(bus_entry
		(at 227.33 71.12)
		(size 2.54 2.54)
		(stroke
			(width 0)
			(type default)
		)
	)
	(bus_entry
		(at 207.01 215.9)
		(size 2.54 2.54)
		(stroke
			(width 0)
			(type default)
		)
	)
	(bus_entry
		(at 158.75 76.2)
		(size 2.54 2.54)
		(stroke
			(width 0)
			(type default)
		)
	)
	(bus_entry
		(at 140.97 243.84)
		(size -2.54 2.54)
		(stroke
			(width 0)
			(type default)
		)
	)
	(bus_entry
		(at 158.75 78.74)
		(size 2.54 2.54)
		(stroke
			(width 0)
			(type default)
		)
	)
	(bus_entry
		(at 140.97 181.61)
		(size -2.54 2.54)
		(stroke
			(width 0)
			(type default)
		)
	)
	(bus_entry
		(at 270.51 200.66)
		(size -2.54 2.54)
		(stroke
			(width 0)
			(type default)
		)
	)
	(bus_entry
		(at 140.97 198.12)
		(size -2.54 2.54)
		(stroke
			(width 0)
			(type default)
		)
	)
	(bus_entry
		(at 158.75 73.66)
		(size 2.54 2.54)
		(stroke
			(width 0)
			(type default)
		)
	)
	(bus_entry
		(at 227.33 53.34)
		(size 2.54 2.54)
		(stroke
			(width 0)
			(type default)
		)
	)
	(bus_entry
		(at 270.51 203.2)
		(size -2.54 2.54)
		(stroke
			(width 0)
			(type default)
		)
	)
	(bus_entry
		(at 227.33 48.26)
		(size 2.54 2.54)
		(stroke
			(width 0)
			(type default)
		)
	)
	(bus_entry
		(at 207.01 208.28)
		(size 2.54 2.54)
		(stroke
			(width 0)
			(type default)
		)
	)
	(bus_entry
		(at 140.97 219.71)
		(size -2.54 2.54)
		(stroke
			(width 0)
			(type default)
		)
	)
	(bus_entry
		(at 140.97 222.25)
		(size -2.54 2.54)
		(stroke
			(width 0)
			(type default)
		)
	)
	(bus_entry
		(at 158.75 43.18)
		(size 2.54 2.54)
		(stroke
			(width 0)
			(type default)
		)
	)
	(bus_entry
		(at 207.01 185.42)
		(size 2.54 2.54)
		(stroke
			(width 0)
			(type default)
		)
	)
	(bus_entry
		(at 227.33 45.72)
		(size 2.54 2.54)
		(stroke
			(width 0)
			(type default)
		)
	)
	(bus_entry
		(at 140.97 184.15)
		(size -2.54 2.54)
		(stroke
			(width 0)
			(type default)
		)
	)
	(bus_entry
		(at 270.51 213.36)
		(size -2.54 2.54)
		(stroke
			(width 0)
			(type default)
		)
	)
	(bus_entry
		(at 140.97 160.02)
		(size -2.54 2.54)
		(stroke
			(width 0)
			(type default)
		)
	)
	(bus_entry
		(at 207.01 193.04)
		(size 2.54 2.54)
		(stroke
			(width 0)
			(type default)
		)
	)
	(bus_entry
		(at 158.75 38.1)
		(size 2.54 2.54)
		(stroke
			(width 0)
			(type default)
		)
	)
	(bus_entry
		(at 227.33 63.5)
		(size 2.54 2.54)
		(stroke
			(width 0)
			(type default)
		)
	)
	(bus_entry
		(at 270.51 208.28)
		(size -2.54 2.54)
		(stroke
			(width 0)
			(type default)
		)
	)
	(bus_entry
		(at 140.97 176.53)
		(size -2.54 2.54)
		(stroke
			(width 0)
			(type default)
		)
	)
	(bus_entry
		(at 140.97 219.71)
		(size -2.54 2.54)
		(stroke
			(width 0)
			(type default)
		)
	)
	(bus_entry
		(at 140.97 222.25)
		(size -2.54 2.54)
		(stroke
			(width 0)
			(type default)
		)
	)
	(bus_entry
		(at 227.33 60.96)
		(size 2.54 2.54)
		(stroke
			(width 0)
			(type default)
		)
	)
	(bus_entry
		(at 270.51 198.12)
		(size -2.54 2.54)
		(stroke
			(width 0)
			(type default)
		)
	)
	(bus_entry
		(at 158.75 81.28)
		(size 2.54 2.54)
		(stroke
			(width 0)
			(type default)
		)
	)
	(wire
		(pts
			(xy 123.19 232.41) (xy 124.46 232.41)
		)
		(stroke
			(width 0)
			(type default)
		)
	)
	(polyline
		(pts
			(xy 12.7 134.62) (xy 406.4 134.62)
		)
		(stroke
			(width 0)
			(type default)
		)
	)
	(wire
		(pts
			(xy 220.98 220.98) (xy 222.25 220.98)
		)
		(stroke
			(width 0)
			(type default)
		)
	)
	(bus
		(pts
			(xy 158.75 45.72) (xy 158.75 55.88)
		)
		(stroke
			(width 0)
			(type default)
		)
	)
	(wire
		(pts
			(xy 124.46 205.74) (xy 124.46 208.28)
		)
		(stroke
			(width 0)
			(type default)
		)
	)
	(wire
		(pts
			(xy 242.57 195.58) (xy 233.68 195.58)
		)
		(stroke
			(width 0)
			(type default)
		)
	)
	(wire
		(pts
			(xy 229.87 81.28) (xy 238.76 81.28)
		)
		(stroke
			(width 0)
			(type default)
		)
	)
	(wire
		(pts
			(xy 229.87 43.18) (xy 260.35 43.18)
		)
		(stroke
			(width 0)
			(type default)
		)
	)
	(wire
		(pts
			(xy 138.43 179.07) (xy 123.19 179.07)
		)
		(stroke
			(width 0)
			(type default)
		)
	)
	(wire
		(pts
			(xy 220.98 205.74) (xy 222.25 205.74)
		)
		(stroke
			(width 0)
			(type default)
		)
	)
	(wire
		(pts
			(xy 161.29 76.2) (xy 177.8 76.2)
		)
		(stroke
			(width 0)
			(type default)
		)
	)
	(wire
		(pts
			(xy 123.19 208.28) (xy 124.46 208.28)
		)
		(stroke
			(width 0)
			(type default)
		)
	)
	(wire
		(pts
			(xy 254 218.44) (xy 267.97 218.44)
		)
		(stroke
			(width 0)
			(type default)
		)
	)
	(bus
		(pts
			(xy 140.97 224.79) (xy 140.97 227.33)
		)
		(stroke
			(width 0)
			(type default)
		)
	)
	(wire
		(pts
			(xy 287.02 88.9) (xy 287.02 91.44)
		)
		(stroke
			(width 0)
			(type default)
		)
	)
	(bus
		(pts
			(xy 227.33 36.83) (xy 227.33 38.1)
		)
		(stroke
			(width 0)
			(type default)
		)
	)
	(wire
		(pts
			(xy 236.22 190.5) (xy 236.22 187.96)
		)
		(stroke
			(width 0)
			(type default)
		)
	)
	(wire
		(pts
			(xy 245.11 91.44) (xy 252.73 91.44)
		)
		(stroke
			(width 0)
			(type default)
		)
	)
	(wire
		(pts
			(xy 138.43 241.3) (xy 123.19 241.3)
		)
		(stroke
			(width 0)
			(type default)
		)
	)
	(wire
		(pts
			(xy 177.8 68.58) (xy 176.53 68.58)
		)
		(stroke
			(width 0)
			(type default)
		)
	)
	(wire
		(pts
			(xy 256.54 83.82) (xy 260.35 83.82)
		)
		(stroke
			(width 0)
			(type default)
		)
	)
	(bus
		(pts
			(xy 140.97 246.38) (xy 140.97 243.84)
		)
		(stroke
			(width 0)
			(type default)
		)
	)
	(wire
		(pts
			(xy 259.08 172.72) (xy 259.08 175.26)
		)
		(stroke
			(width 0)
			(type default)
		)
	)
	(wire
		(pts
			(xy 138.43 167.64) (xy 123.19 167.64)
		)
		(stroke
			(width 0)
			(type default)
		)
	)
	(bus
		(pts
			(xy 203.2 180.34) (xy 207.01 180.34)
		)
		(stroke
			(width 0)
			(type default)
		)
	)
	(wire
		(pts
			(xy 229.87 66.04) (xy 260.35 66.04)
		)
		(stroke
			(width 0)
			(type default)
		)
	)
	(wire
		(pts
			(xy 176.53 86.36) (xy 176.53 87.63)
		)
		(stroke
			(width 0)
			(type default)
		)
	)
	(bus
		(pts
			(xy 140.97 157.48) (xy 140.97 160.02)
		)
		(stroke
			(width 0)
			(type default)
		)
	)
	(bus
		(pts
			(xy 158.75 38.1) (xy 158.75 40.64)
		)
		(stroke
			(width 0)
			(type default)
		)
	)
	(wire
		(pts
			(xy 285.75 78.74) (xy 287.02 78.74)
		)
		(stroke
			(width 0)
			(type default)
		)
	)
	(wire
		(pts
			(xy 273.05 171.45) (xy 273.05 172.72)
		)
		(stroke
			(width 0)
			(type default)
		)
	)
	(wire
		(pts
			(xy 161.29 58.42) (xy 177.8 58.42)
		)
		(stroke
			(width 0)
			(type default)
		)
	)
	(wire
		(pts
			(xy 285.75 88.9) (xy 287.02 88.9)
		)
		(stroke
			(width 0)
			(type default)
		)
	)
	(wire
		(pts
			(xy 138.43 165.1) (xy 123.19 165.1)
		)
		(stroke
			(width 0)
			(type default)
		)
	)
	(wire
		(pts
			(xy 246.38 256.54) (xy 247.65 256.54)
		)
		(stroke
			(width 0)
			(type default)
		)
	)
	(bus
		(pts
			(xy 140.97 181.61) (xy 140.97 184.15)
		)
		(stroke
			(width 0)
			(type default)
		)
	)
	(bus
		(pts
			(xy 140.97 241.3) (xy 140.97 243.84)
		)
		(stroke
			(width 0)
			(type default)
		)
	)
	(wire
		(pts
			(xy 247.65 256.54) (xy 247.65 259.08)
		)
		(stroke
			(width 0)
			(type default)
		)
	)
	(bus
		(pts
			(xy 140.97 162.56) (xy 140.97 165.1)
		)
		(stroke
			(width 0)
			(type default)
		)
	)
	(wire
		(pts
			(xy 233.68 187.96) (xy 236.22 187.96)
		)
		(stroke
			(width 0)
			(type default)
		)
	)
	(wire
		(pts
			(xy 209.55 193.04) (xy 222.25 193.04)
		)
		(stroke
			(width 0)
			(type default)
		)
	)
	(wire
		(pts
			(xy 218.44 91.44) (xy 226.06 91.44)
		)
		(stroke
			(width 0)
			(type default)
		)
	)
	(wire
		(pts
			(xy 220.98 205.74) (xy 220.98 213.36)
		)
		(stroke
			(width 0)
			(type default)
		)
	)
	(wire
		(pts
			(xy 161.29 48.26) (xy 177.8 48.26)
		)
		(stroke
			(width 0)
			(type default)
		)
	)
	(bus
		(pts
			(xy 227.33 63.5) (xy 227.33 71.12)
		)
		(stroke
			(width 0)
			(type default)
		)
	)
	(wire
		(pts
			(xy 209.55 208.28) (xy 222.25 208.28)
		)
		(stroke
			(width 0)
			(type default)
		)
	)
	(wire
		(pts
			(xy 138.43 229.87) (xy 123.19 229.87)
		)
		(stroke
			(width 0)
			(type default)
		)
	)
	(bus
		(pts
			(xy 227.33 60.96) (xy 227.33 63.5)
		)
		(stroke
			(width 0)
			(type default)
		)
	)
	(wire
		(pts
			(xy 255.27 102.87) (xy 255.27 100.33)
		)
		(stroke
			(width 0)
			(type default)
		)
	)
	(bus
		(pts
			(xy 158.75 40.64) (xy 158.75 43.18)
		)
		(stroke
			(width 0)
			(type default)
		)
	)
	(bus
		(pts
			(xy 207.01 180.34) (xy 207.01 182.88)
		)
		(stroke
			(width 0)
			(type default)
		)
	)
	(wire
		(pts
			(xy 231.14 91.44) (xy 237.49 91.44)
		)
		(stroke
			(width 0)
			(type default)
		)
	)
	(bus
		(pts
			(xy 207.01 205.74) (xy 207.01 208.28)
		)
		(stroke
			(width 0)
			(type default)
		)
	)
	(wire
		(pts
			(xy 209.55 187.96) (xy 222.25 187.96)
		)
		(stroke
			(width 0)
			(type default)
		)
	)
	(bus
		(pts
			(xy 140.97 165.1) (xy 140.97 176.53)
		)
		(stroke
			(width 0)
			(type default)
		)
	)
	(wire
		(pts
			(xy 161.29 45.72) (xy 177.8 45.72)
		)
		(stroke
			(width 0)
			(type default)
		)
	)
	(wire
		(pts
			(xy 138.43 200.66) (xy 123.19 200.66)
		)
		(stroke
			(width 0)
			(type default)
		)
	)
	(wire
		(pts
			(xy 124.46 208.28) (xy 124.46 209.55)
		)
		(stroke
			(width 0)
			(type default)
		)
	)
	(wire
		(pts
			(xy 267.97 205.74) (xy 254 205.74)
		)
		(stroke
			(width 0)
			(type default)
		)
	)
	(wire
		(pts
			(xy 229.87 78.74) (xy 238.76 78.74)
		)
		(stroke
			(width 0)
			(type default)
		)
	)
	(wire
		(pts
			(xy 177.8 50.8) (xy 176.53 50.8)
		)
		(stroke
			(width 0)
			(type default)
		)
	)
	(wire
		(pts
			(xy 242.57 194.31) (xy 242.57 195.58)
		)
		(stroke
			(width 0)
			(type default)
		)
	)
	(wire
		(pts
			(xy 220.98 213.36) (xy 222.25 213.36)
		)
		(stroke
			(width 0)
			(type default)
		)
	)
	(wire
		(pts
			(xy 255.27 91.44) (xy 260.35 91.44)
		)
		(stroke
			(width 0)
			(type default)
		)
	)
	(wire
		(pts
			(xy 236.22 187.96) (xy 236.22 185.42)
		)
		(stroke
			(width 0)
			(type default)
		)
	)
	(wire
		(pts
			(xy 267.97 210.82) (xy 254 210.82)
		)
		(stroke
			(width 0)
			(type default)
		)
	)
	(wire
		(pts
			(xy 123.19 251.46) (xy 124.46 251.46)
		)
		(stroke
			(width 0)
			(type default)
		)
	)
	(wire
		(pts
			(xy 177.8 86.36) (xy 176.53 86.36)
		)
		(stroke
			(width 0)
			(type default)
		)
	)
	(bus
		(pts
			(xy 227.33 71.12) (xy 227.33 73.66)
		)
		(stroke
			(width 0)
			(type default)
		)
	)
	(wire
		(pts
			(xy 256.54 78.74) (xy 260.35 78.74)
		)
		(stroke
			(width 0)
			(type default)
		)
	)
	(bus
		(pts
			(xy 158.75 58.42) (xy 158.75 60.96)
		)
		(stroke
			(width 0)
			(type default)
		)
	)
	(wire
		(pts
			(xy 229.87 48.26) (xy 260.35 48.26)
		)
		(stroke
			(width 0)
			(type default)
		)
	)
	(wire
		(pts
			(xy 209.55 218.44) (xy 222.25 218.44)
		)
		(stroke
			(width 0)
			(type default)
		)
	)
	(bus
		(pts
			(xy 207.01 185.42) (xy 207.01 190.5)
		)
		(stroke
			(width 0)
			(type default)
		)
	)
	(wire
		(pts
			(xy 238.76 181.61) (xy 238.76 180.34)
		)
		(stroke
			(width 0)
			(type default)
		)
	)
	(wire
		(pts
			(xy 238.76 172.72) (xy 238.76 175.26)
		)
		(stroke
			(width 0)
			(type default)
		)
	)
	(wire
		(pts
			(xy 285.75 81.28) (xy 287.02 81.28)
		)
		(stroke
			(width 0)
			(type default)
		)
	)
	(wire
		(pts
			(xy 287.02 83.82) (xy 287.02 86.36)
		)
		(stroke
			(width 0)
			(type default)
		)
	)
	(wire
		(pts
			(xy 245.11 100.33) (xy 245.11 102.87)
		)
		(stroke
			(width 0)
			(type default)
		)
	)
	(bus
		(pts
			(xy 207.01 190.5) (xy 207.01 193.04)
		)
		(stroke
			(width 0)
			(type default)
		)
	)
	(wire
		(pts
			(xy 123.19 189.23) (xy 124.46 189.23)
		)
		(stroke
			(width 0)
			(type default)
		)
	)
	(wire
		(pts
			(xy 252.73 73.66) (xy 248.92 73.66)
		)
		(stroke
			(width 0)
			(type default)
		)
	)
	(wire
		(pts
			(xy 252.73 76.2) (xy 248.92 76.2)
		)
		(stroke
			(width 0)
			(type default)
		)
	)
	(wire
		(pts
			(xy 220.98 198.12) (xy 220.98 205.74)
		)
		(stroke
			(width 0)
			(type default)
		)
	)
	(wire
		(pts
			(xy 161.29 81.28) (xy 177.8 81.28)
		)
		(stroke
			(width 0)
			(type default)
		)
	)
	(wire
		(pts
			(xy 209.55 185.42) (xy 222.25 185.42)
		)
		(stroke
			(width 0)
			(type default)
		)
	)
	(wire
		(pts
			(xy 285.75 177.8) (xy 285.75 179.07)
		)
		(stroke
			(width 0)
			(type default)
		)
	)
	(bus
		(pts
			(xy 270.51 203.2) (xy 270.51 205.74)
		)
		(stroke
			(width 0)
			(type default)
		)
	)
	(wire
		(pts
			(xy 255.27 91.44) (xy 255.27 95.25)
		)
		(stroke
			(width 0)
			(type default)
		)
	)
	(bus
		(pts
			(xy 140.97 160.02) (xy 140.97 162.56)
		)
		(stroke
			(width 0)
			(type default)
		)
	)
	(wire
		(pts
			(xy 209.55 210.82) (xy 222.25 210.82)
		)
		(stroke
			(width 0)
			(type default)
		)
	)
	(wire
		(pts
			(xy 123.19 203.2) (xy 124.46 203.2)
		)
		(stroke
			(width 0)
			(type default)
		)
	)
	(bus
		(pts
			(xy 140.97 153.67) (xy 140.97 157.48)
		)
		(stroke
			(width 0)
			(type default)
		)
	)
	(wire
		(pts
			(xy 124.46 189.23) (xy 124.46 190.5)
		)
		(stroke
			(width 0)
			(type default)
		)
	)
	(wire
		(pts
			(xy 252.73 91.44) (xy 255.27 91.44)
		)
		(stroke
			(width 0)
			(type default)
		)
	)
	(wire
		(pts
			(xy 273.05 172.72) (xy 270.51 172.72)
		)
		(stroke
			(width 0)
			(type default)
		)
	)
	(wire
		(pts
			(xy 243.84 205.74) (xy 233.68 205.74)
		)
		(stroke
			(width 0)
			(type default)
		)
	)
	(bus
		(pts
			(xy 158.75 76.2) (xy 158.75 78.74)
		)
		(stroke
			(width 0)
			(type default)
		)
	)
	(wire
		(pts
			(xy 209.55 195.58) (xy 222.25 195.58)
		)
		(stroke
			(width 0)
			(type default)
		)
	)
	(wire
		(pts
			(xy 138.43 198.12) (xy 123.19 198.12)
		)
		(stroke
			(width 0)
			(type default)
		)
	)
	(bus
		(pts
			(xy 227.33 55.88) (xy 227.33 60.96)
		)
		(stroke
			(width 0)
			(type default)
		)
	)
	(wire
		(pts
			(xy 234.95 198.12) (xy 234.95 220.98)
		)
		(stroke
			(width 0)
			(type default)
		)
	)
	(bus
		(pts
			(xy 227.33 45.72) (xy 227.33 48.26)
		)
		(stroke
			(width 0)
			(type default)
		)
	)
	(bus
		(pts
			(xy 207.01 193.04) (xy 207.01 198.12)
		)
		(stroke
			(width 0)
			(type default)
		)
	)
	(bus
		(pts
			(xy 140.97 176.53) (xy 140.97 179.07)
		)
		(stroke
			(width 0)
			(type default)
		)
	)
	(wire
		(pts
			(xy 233.68 190.5) (xy 236.22 190.5)
		)
		(stroke
			(width 0)
			(type default)
		)
	)
	(wire
		(pts
			(xy 161.29 63.5) (xy 177.8 63.5)
		)
		(stroke
			(width 0)
			(type default)
		)
	)
	(bus
		(pts
			(xy 140.97 219.71) (xy 140.97 222.25)
		)
		(stroke
			(width 0)
			(type default)
		)
	)
	(bus
		(pts
			(xy 227.33 76.2) (xy 227.33 78.74)
		)
		(stroke
			(width 0)
			(type default)
		)
	)
	(wire
		(pts
			(xy 161.29 43.18) (xy 177.8 43.18)
		)
		(stroke
			(width 0)
			(type default)
		)
	)
	(wire
		(pts
			(xy 267.97 200.66) (xy 254 200.66)
		)
		(stroke
			(width 0)
			(type default)
		)
	)
	(wire
		(pts
			(xy 243.84 208.28) (xy 233.68 208.28)
		)
		(stroke
			(width 0)
			(type default)
		)
	)
	(wire
		(pts
			(xy 242.57 91.44) (xy 245.11 91.44)
		)
		(stroke
			(width 0)
			(type default)
		)
	)
	(wire
		(pts
			(xy 161.29 83.82) (xy 177.8 83.82)
		)
		(stroke
			(width 0)
			(type default)
		)
	)
	(wire
		(pts
			(xy 285.75 91.44) (xy 287.02 91.44)
		)
		(stroke
			(width 0)
			(type default)
		)
	)
	(wire
		(pts
			(xy 138.43 162.56) (xy 123.19 162.56)
		)
		(stroke
			(width 0)
			(type default)
		)
	)
	(wire
		(pts
			(xy 233.68 233.68) (xy 234.95 233.68)
		)
		(stroke
			(width 0)
			(type default)
		)
	)
	(bus
		(pts
			(xy 157.48 36.83) (xy 158.75 36.83)
		)
		(stroke
			(width 0)
			(type default)
		)
	)
	(wire
		(pts
			(xy 229.87 50.8) (xy 260.35 50.8)
		)
		(stroke
			(width 0)
			(type default)
		)
	)
	(wire
		(pts
			(xy 252.73 78.74) (xy 248.92 78.74)
		)
		(stroke
			(width 0)
			(type default)
		)
	)
	(bus
		(pts
			(xy 207.01 213.36) (xy 207.01 215.9)
		)
		(stroke
			(width 0)
			(type default)
		)
	)
	(wire
		(pts
			(xy 233.68 198.12) (xy 234.95 198.12)
		)
		(stroke
			(width 0)
			(type default)
		)
	)
	(wire
		(pts
			(xy 222.25 182.88) (xy 220.98 182.88)
		)
		(stroke
			(width 0)
			(type default)
		)
	)
	(wire
		(pts
			(xy 229.87 73.66) (xy 238.76 73.66)
		)
		(stroke
			(width 0)
			(type default)
		)
	)
	(wire
		(pts
			(xy 220.98 220.98) (xy 220.98 236.22)
		)
		(stroke
			(width 0)
			(type default)
		)
	)
	(wire
		(pts
			(xy 287.02 78.74) (xy 287.02 81.28)
		)
		(stroke
			(width 0)
			(type default)
		)
	)
	(wire
		(pts
			(xy 285.75 83.82) (xy 287.02 83.82)
		)
		(stroke
			(width 0)
			(type default)
		)
	)
	(wire
		(pts
			(xy 234.95 220.98) (xy 234.95 233.68)
		)
		(stroke
			(width 0)
			(type default)
		)
	)
	(bus
		(pts
			(xy 140.97 179.07) (xy 140.97 181.61)
		)
		(stroke
			(width 0)
			(type default)
		)
	)
	(bus
		(pts
			(xy 270.51 215.9) (xy 270.51 213.36)
		)
		(stroke
			(width 0)
			(type default)
		)
	)
	(bus
		(pts
			(xy 140.97 227.33) (xy 140.97 238.76)
		)
		(stroke
			(width 0)
			(type default)
		)
	)
	(wire
		(pts
			(xy 243.84 215.9) (xy 233.68 215.9)
		)
		(stroke
			(width 0)
			(type default)
		)
	)
	(wire
		(pts
			(xy 138.43 160.02) (xy 123.19 160.02)
		)
		(stroke
			(width 0)
			(type default)
		)
	)
	(bus
		(pts
			(xy 140.97 238.76) (xy 140.97 241.3)
		)
		(stroke
			(width 0)
			(type default)
		)
	)
	(wire
		(pts
			(xy 229.87 63.5) (xy 260.35 63.5)
		)
		(stroke
			(width 0)
			(type default)
		)
	)
	(wire
		(pts
			(xy 245.11 91.44) (xy 245.11 95.25)
		)
		(stroke
			(width 0)
			(type default)
		)
	)
	(bus
		(pts
			(xy 270.51 208.28) (xy 270.51 210.82)
		)
		(stroke
			(width 0)
			(type default)
		)
	)
	(wire
		(pts
			(xy 233.68 193.04) (xy 236.22 193.04)
		)
		(stroke
			(width 0)
			(type default)
		)
	)
	(bus
		(pts
			(xy 158.75 78.74) (xy 158.75 81.28)
		)
		(stroke
			(width 0)
			(type default)
		)
	)
	(bus
		(pts
			(xy 226.06 36.83) (xy 227.33 36.83)
		)
		(stroke
			(width 0)
			(type default)
		)
	)
	(bus
		(pts
			(xy 270.51 198.12) (xy 270.51 200.66)
		)
		(stroke
			(width 0)
			(type default)
		)
	)
	(bus
		(pts
			(xy 140.97 184.15) (xy 140.97 195.58)
		)
		(stroke
			(width 0)
			(type default)
		)
	)
	(wire
		(pts
			(xy 267.97 215.9) (xy 254 215.9)
		)
		(stroke
			(width 0)
			(type default)
		)
	)
	(wire
		(pts
			(xy 234.95 233.68) (xy 234.95 236.22)
		)
		(stroke
			(width 0)
			(type default)
		)
	)
	(wire
		(pts
			(xy 233.68 182.88) (xy 234.95 182.88)
		)
		(stroke
			(width 0)
			(type default)
		)
	)
	(wire
		(pts
			(xy 161.29 40.64) (xy 177.8 40.64)
		)
		(stroke
			(width 0)
			(type default)
		)
	)
	(wire
		(pts
			(xy 209.55 215.9) (xy 222.25 215.9)
		)
		(stroke
			(width 0)
			(type default)
		)
	)
	(wire
		(pts
			(xy 124.46 170.18) (xy 124.46 171.45)
		)
		(stroke
			(width 0)
			(type default)
		)
	)
	(wire
		(pts
			(xy 233.68 218.44) (xy 243.84 218.44)
		)
		(stroke
			(width 0)
			(type default)
		)
	)
	(wire
		(pts
			(xy 161.29 78.74) (xy 177.8 78.74)
		)
		(stroke
			(width 0)
			(type default)
		)
	)
	(wire
		(pts
			(xy 138.43 224.79) (xy 123.19 224.79)
		)
		(stroke
			(width 0)
			(type default)
		)
	)
	(wire
		(pts
			(xy 252.73 81.28) (xy 248.92 81.28)
		)
		(stroke
			(width 0)
			(type default)
		)
	)
	(wire
		(pts
			(xy 259.08 172.72) (xy 265.43 172.72)
		)
		(stroke
			(width 0)
			(type default)
		)
	)
	(bus
		(pts
			(xy 207.01 182.88) (xy 207.01 185.42)
		)
		(stroke
			(width 0)
			(type default)
		)
	)
	(wire
		(pts
			(xy 233.68 220.98) (xy 234.95 220.98)
		)
		(stroke
			(width 0)
			(type default)
		)
	)
	(bus
		(pts
			(xy 270.51 210.82) (xy 270.51 213.36)
		)
		(stroke
			(width 0)
			(type default)
		)
	)
	(wire
		(pts
			(xy 256.54 71.12) (xy 260.35 71.12)
		)
		(stroke
			(width 0)
			(type default)
		)
	)
	(wire
		(pts
			(xy 218.44 90.17) (xy 218.44 91.44)
		)
		(stroke
			(width 0)
			(type default)
		)
	)
	(bus
		(pts
			(xy 227.33 48.26) (xy 227.33 53.34)
		)
		(stroke
			(width 0)
			(type default)
		)
	)
	(bus
		(pts
			(xy 140.97 195.58) (xy 140.97 198.12)
		)
		(stroke
			(width 0)
			(type default)
		)
	)
	(wire
		(pts
			(xy 209.55 200.66) (xy 222.25 200.66)
		)
		(stroke
			(width 0)
			(type default)
		)
	)
	(wire
		(pts
			(xy 290.83 171.45) (xy 290.83 172.72)
		)
		(stroke
			(width 0)
			(type default)
		)
	)
	(wire
		(pts
			(xy 161.29 66.04) (xy 177.8 66.04)
		)
		(stroke
			(width 0)
			(type default)
		)
	)
	(bus
		(pts
			(xy 143.51 153.67) (xy 140.97 153.67)
		)
		(stroke
			(width 0)
			(type default)
		)
	)
	(bus
		(pts
			(xy 270.51 205.74) (xy 270.51 208.28)
		)
		(stroke
			(width 0)
			(type default)
		)
	)
	(bus
		(pts
			(xy 142.24 219.71) (xy 140.97 219.71)
		)
		(stroke
			(width 0)
			(type default)
		)
	)
	(wire
		(pts
			(xy 138.43 184.15) (xy 123.19 184.15)
		)
		(stroke
			(width 0)
			(type default)
		)
	)
	(bus
		(pts
			(xy 158.75 36.83) (xy 158.75 38.1)
		)
		(stroke
			(width 0)
			(type default)
		)
	)
	(wire
		(pts
			(xy 220.98 190.5) (xy 220.98 198.12)
		)
		(stroke
			(width 0)
			(type default)
		)
	)
	(wire
		(pts
			(xy 238.76 172.72) (xy 259.08 172.72)
		)
		(stroke
			(width 0)
			(type default)
		)
	)
	(wire
		(pts
			(xy 243.84 210.82) (xy 233.68 210.82)
		)
		(stroke
			(width 0)
			(type default)
		)
	)
	(wire
		(pts
			(xy 138.43 227.33) (xy 123.19 227.33)
		)
		(stroke
			(width 0)
			(type default)
		)
	)
	(wire
		(pts
			(xy 123.19 170.18) (xy 124.46 170.18)
		)
		(stroke
			(width 0)
			(type default)
		)
	)
	(wire
		(pts
			(xy 287.02 81.28) (xy 287.02 83.82)
		)
		(stroke
			(width 0)
			(type default)
		)
	)
	(bus
		(pts
			(xy 140.97 224.79) (xy 142.24 224.79)
		)
		(stroke
			(width 0)
			(type default)
		)
	)
	(bus
		(pts
			(xy 158.75 63.5) (xy 158.75 73.66)
		)
		(stroke
			(width 0)
			(type default)
		)
	)
	(wire
		(pts
			(xy 220.98 182.88) (xy 220.98 190.5)
		)
		(stroke
			(width 0)
			(type default)
		)
	)
	(bus
		(pts
			(xy 207.01 208.28) (xy 207.01 213.36)
		)
		(stroke
			(width 0)
			(type default)
		)
	)
	(wire
		(pts
			(xy 124.46 232.41) (xy 124.46 233.68)
		)
		(stroke
			(width 0)
			(type default)
		)
	)
	(wire
		(pts
			(xy 124.46 203.2) (xy 124.46 205.74)
		)
		(stroke
			(width 0)
			(type default)
		)
	)
	(wire
		(pts
			(xy 138.43 222.25) (xy 123.19 222.25)
		)
		(stroke
			(width 0)
			(type default)
		)
	)
	(wire
		(pts
			(xy 220.98 213.36) (xy 220.98 220.98)
		)
		(stroke
			(width 0)
			(type default)
		)
	)
	(bus
		(pts
			(xy 158.75 73.66) (xy 158.75 76.2)
		)
		(stroke
			(width 0)
			(type default)
		)
	)
	(wire
		(pts
			(xy 229.87 76.2) (xy 238.76 76.2)
		)
		(stroke
			(width 0)
			(type default)
		)
	)
	(wire
		(pts
			(xy 222.25 190.5) (xy 220.98 190.5)
		)
		(stroke
			(width 0)
			(type default)
		)
	)
	(bus
		(pts
			(xy 227.33 38.1) (xy 227.33 40.64)
		)
		(stroke
			(width 0)
			(type default)
		)
	)
	(bus
		(pts
			(xy 207.01 198.12) (xy 207.01 200.66)
		)
		(stroke
			(width 0)
			(type default)
		)
	)
	(bus
		(pts
			(xy 227.33 53.34) (xy 227.33 55.88)
		)
		(stroke
			(width 0)
			(type default)
		)
	)
	(bus
		(pts
			(xy 227.33 40.64) (xy 227.33 45.72)
		)
		(stroke
			(width 0)
			(type default)
		)
	)
	(wire
		(pts
			(xy 176.53 68.58) (xy 176.53 69.85)
		)
		(stroke
			(width 0)
			(type default)
		)
	)
	(wire
		(pts
			(xy 138.43 186.69) (xy 123.19 186.69)
		)
		(stroke
			(width 0)
			(type default)
		)
	)
	(wire
		(pts
			(xy 267.97 203.2) (xy 254 203.2)
		)
		(stroke
			(width 0)
			(type default)
		)
	)
	(wire
		(pts
			(xy 236.22 193.04) (xy 236.22 190.5)
		)
		(stroke
			(width 0)
			(type default)
		)
	)
	(wire
		(pts
			(xy 285.75 86.36) (xy 287.02 86.36)
		)
		(stroke
			(width 0)
			(type default)
		)
	)
	(wire
		(pts
			(xy 256.54 73.66) (xy 260.35 73.66)
		)
		(stroke
			(width 0)
			(type default)
		)
	)
	(wire
		(pts
			(xy 236.22 172.72) (xy 238.76 172.72)
		)
		(stroke
			(width 0)
			(type default)
		)
	)
	(wire
		(pts
			(xy 259.08 180.34) (xy 259.08 181.61)
		)
		(stroke
			(width 0)
			(type default)
		)
	)
	(wire
		(pts
			(xy 220.98 198.12) (xy 222.25 198.12)
		)
		(stroke
			(width 0)
			(type default)
		)
	)
	(bus
		(pts
			(xy 158.75 60.96) (xy 158.75 63.5)
		)
		(stroke
			(width 0)
			(type default)
		)
	)
	(wire
		(pts
			(xy 243.84 200.66) (xy 233.68 200.66)
		)
		(stroke
			(width 0)
			(type default)
		)
	)
	(wire
		(pts
			(xy 290.83 177.8) (xy 290.83 179.07)
		)
		(stroke
			(width 0)
			(type default)
		)
	)
	(wire
		(pts
			(xy 267.97 213.36) (xy 254 213.36)
		)
		(stroke
			(width 0)
			(type default)
		)
	)
	(wire
		(pts
			(xy 138.43 246.38) (xy 123.19 246.38)
		)
		(stroke
			(width 0)
			(type default)
		)
	)
	(bus
		(pts
			(xy 270.51 203.2) (xy 271.78 203.2)
		)
		(stroke
			(width 0)
			(type default)
		)
	)
	(bus
		(pts
			(xy 158.75 55.88) (xy 158.75 58.42)
		)
		(stroke
			(width 0)
			(type default)
		)
	)
	(wire
		(pts
			(xy 124.46 251.46) (xy 124.46 252.73)
		)
		(stroke
			(width 0)
			(type default)
		)
	)
	(wire
		(pts
			(xy 236.22 172.72) (xy 236.22 185.42)
		)
		(stroke
			(width 0)
			(type default)
		)
	)
	(wire
		(pts
			(xy 243.84 203.2) (xy 233.68 203.2)
		)
		(stroke
			(width 0)
			(type default)
		)
	)
	(wire
		(pts
			(xy 287.02 86.36) (xy 287.02 88.9)
		)
		(stroke
			(width 0)
			(type default)
		)
	)
	(wire
		(pts
			(xy 252.73 90.17) (xy 252.73 91.44)
		)
		(stroke
			(width 0)
			(type default)
		)
	)
	(bus
		(pts
			(xy 158.75 43.18) (xy 158.75 45.72)
		)
		(stroke
			(width 0)
			(type default)
		)
	)
	(bus
		(pts
			(xy 207.01 200.66) (xy 207.01 205.74)
		)
		(stroke
			(width 0)
			(type default)
		)
	)
	(wire
		(pts
			(xy 243.84 213.36) (xy 233.68 213.36)
		)
		(stroke
			(width 0)
			(type default)
		)
	)
	(wire
		(pts
			(xy 138.43 243.84) (xy 123.19 243.84)
		)
		(stroke
			(width 0)
			(type default)
		)
	)
	(wire
		(pts
			(xy 267.97 208.28) (xy 254 208.28)
		)
		(stroke
			(width 0)
			(type default)
		)
	)
	(wire
		(pts
			(xy 123.19 205.74) (xy 124.46 205.74)
		)
		(stroke
			(width 0)
			(type default)
		)
	)
	(wire
		(pts
			(xy 229.87 55.88) (xy 260.35 55.88)
		)
		(stroke
			(width 0)
			(type default)
		)
	)
	(wire
		(pts
			(xy 176.53 50.8) (xy 176.53 52.07)
		)
		(stroke
			(width 0)
			(type default)
		)
	)
	(wire
		(pts
			(xy 138.43 248.92) (xy 123.19 248.92)
		)
		(stroke
			(width 0)
			(type default)
		)
	)
	(wire
		(pts
			(xy 161.29 60.96) (xy 177.8 60.96)
		)
		(stroke
			(width 0)
			(type default)
		)
	)
	(wire
		(pts
			(xy 229.87 40.64) (xy 260.35 40.64)
		)
		(stroke
			(width 0)
			(type default)
		)
	)
	(wire
		(pts
			(xy 233.68 185.42) (xy 236.22 185.42)
		)
		(stroke
			(width 0)
			(type default)
		)
	)
	(wire
		(pts
			(xy 209.55 203.2) (xy 222.25 203.2)
		)
		(stroke
			(width 0)
			(type default)
		)
	)
	(wire
		(pts
			(xy 287.02 91.44) (xy 287.02 92.71)
		)
		(stroke
			(width 0)
			(type default)
		)
	)
	(wire
		(pts
			(xy 229.87 58.42) (xy 260.35 58.42)
		)
		(stroke
			(width 0)
			(type default)
		)
	)
	(bus
		(pts
			(xy 271.78 198.12) (xy 270.51 198.12)
		)
		(stroke
			(width 0)
			(type default)
		)
	)
	(wire
		(pts
			(xy 234.95 182.88) (xy 234.95 198.12)
		)
		(stroke
			(width 0)
			(type default)
		)
	)
	(wire
		(pts
			(xy 138.43 181.61) (xy 123.19 181.61)
		)
		(stroke
			(width 0)
			(type default)
		)
	)
	(bus
		(pts
			(xy 227.33 73.66) (xy 227.33 76.2)
		)
		(stroke
			(width 0)
			(type default)
		)
	)
	(wire
		(pts
			(xy 285.75 171.45) (xy 285.75 172.72)
		)
		(stroke
			(width 0)
			(type default)
		)
	)
	(label "DSICtrl.~{IRQ2}"
		(at 125.73 229.87 0)
		(effects
			(font
				(size 1.27 1.27)
			)
			(justify left bottom)
		)
	)
	(label "HDMI.HPD"
		(at 162.56 76.2 0)
		(effects
			(font
				(size 1.27 1.27)
			)
			(justify left bottom)
		)
	)
	(label "HDMI.SDA"
		(at 162.56 83.82 0)
		(effects
			(font
				(size 1.27 1.27)
			)
			(justify left bottom)
		)
	)
	(label "DSI.D3_N"
		(at 209.55 185.42 0)
		(effects
			(font
				(size 1.27 1.27)
			)
			(justify left bottom)
		)
	)
	(label "HDMI.SCL"
		(at 162.56 81.28 0)
		(effects
			(font
				(size 1.27 1.27)
			)
			(justify left bottom)
		)
	)
	(label "DSICtrl.IRQ1"
		(at 125.73 227.33 0)
		(effects
			(font
				(size 1.27 1.27)
			)
			(justify left bottom)
		)
	)
	(label "HDMI.CEC"
		(at 229.87 78.74 0)
		(effects
			(font
				(size 1.27 1.27)
			)
			(justify left bottom)
		)
	)
	(label "DSICtrl.EN"
		(at 255.27 210.82 0)
		(effects
			(font
				(size 1.27 1.27)
			)
			(justify left bottom)
		)
	)
	(label "HDMI.D1_N"
		(at 229.87 50.8 0)
		(effects
			(font
				(size 1.27 1.27)
			)
			(justify left bottom)
		)
	)
	(label "DSICtrl.GPIO"
		(at 255.27 218.44 0)
		(effects
			(font
				(size 1.27 1.27)
			)
			(justify left bottom)
		)
	)
	(label "HDMI.D2_N"
		(at 229.87 43.18 0)
		(effects
			(font
				(size 1.27 1.27)
			)
			(justify left bottom)
		)
	)
	(label "DSI.D2_N"
		(at 137.16 165.1 180)
		(effects
			(font
				(size 1.27 1.27)
			)
			(justify right bottom)
		)
	)
	(label "DSICtrl.EN"
		(at 125.73 241.3 0)
		(effects
			(font
				(size 1.27 1.27)
			)
			(justify left bottom)
		)
	)
	(label "DSICtrl.GPIO"
		(at 125.73 248.92 0)
		(effects
			(font
				(size 1.27 1.27)
			)
			(justify left bottom)
		)
	)
	(label "I_{2}C1.SDA"
		(at 125.73 222.25 0)
		(effects
			(font
				(size 1.27 1.27)
			)
			(justify left bottom)
		)
	)
	(label "HDMI.CEC"
		(at 162.56 78.74 0)
		(effects
			(font
				(size 1.27 1.27)
			)
			(justify left bottom)
		)
	)
	(label "HDMI.CLK_N"
		(at 229.87 66.04 0)
		(effects
			(font
				(size 1.27 1.27)
			)
			(justify left bottom)
		)
	)
	(label "DSICtrl.~{IRQ2}"
		(at 255.27 208.28 0)
		(effects
			(font
				(size 1.27 1.27)
			)
			(justify left bottom)
		)
	)
	(label "DSI.CLK_P"
		(at 209.55 218.44 0)
		(effects
			(font
				(size 1.27 1.27)
			)
			(justify left bottom)
		)
	)
	(label "DSI.D3_N"
		(at 137.16 160.02 180)
		(effects
			(font
				(size 1.27 1.27)
			)
			(justify right bottom)
		)
	)
	(label "I_{2}C1.SCL"
		(at 255.27 203.2 0)
		(effects
			(font
				(size 1.27 1.27)
			)
			(justify left bottom)
		)
	)
	(label "DSI.D0_P"
		(at 137.16 186.69 180)
		(effects
			(font
				(size 1.27 1.27)
			)
			(justify right bottom)
		)
	)
	(label "HDMI.D1_N"
		(at 162.56 48.26 0)
		(effects
			(font
				(size 1.27 1.27)
			)
			(justify left bottom)
		)
	)
	(label "DSI.D0_P"
		(at 209.55 210.82 0)
		(effects
			(font
				(size 1.27 1.27)
			)
			(justify left bottom)
		)
	)
	(label "DSI.CLK_P"
		(at 137.16 200.66 180)
		(effects
			(font
				(size 1.27 1.27)
			)
			(justify right bottom)
		)
	)
	(label "HDMI.CLK_N"
		(at 162.56 66.04 0)
		(effects
			(font
				(size 1.27 1.27)
			)
			(justify left bottom)
		)
	)
	(label "DSI.D0_N"
		(at 137.16 184.15 180)
		(effects
			(font
				(size 1.27 1.27)
			)
			(justify right bottom)
		)
	)
	(label "I_{2}C1.SDA"
		(at 255.27 200.66 0)
		(effects
			(font
				(size 1.27 1.27)
			)
			(justify left bottom)
		)
	)
	(label "HDMI.D0_N"
		(at 229.87 58.42 0)
		(effects
			(font
				(size 1.27 1.27)
			)
			(justify left bottom)
		)
	)
	(label "SDA"
		(at 256.54 73.66 0)
		(effects
			(font
				(size 1.27 1.27)
			)
			(justify left bottom)
		)
	)
	(label "HPD"
		(at 252.73 81.28 180)
		(effects
			(font
				(size 1.27 1.27)
			)
			(justify right bottom)
		)
	)
	(label "HDMI.D0_P"
		(at 229.87 55.88 0)
		(effects
			(font
				(size 1.27 1.27)
			)
			(justify left bottom)
		)
	)
	(label "HDMI.D1_P"
		(at 162.56 45.72 0)
		(effects
			(font
				(size 1.27 1.27)
			)
			(justify left bottom)
		)
	)
	(label "HDMI.SCL"
		(at 229.87 76.2 0)
		(effects
			(font
				(size 1.27 1.27)
			)
			(justify left bottom)
		)
	)
	(label "HDMI.D2_P"
		(at 162.56 40.64 0)
		(effects
			(font
				(size 1.27 1.27)
			)
			(justify left bottom)
		)
	)
	(label "I_{2}C1.SCL"
		(at 125.73 224.79 0)
		(effects
			(font
				(size 1.27 1.27)
			)
			(justify left bottom)
		)
	)
	(label "HDMI.D0_N"
		(at 162.56 60.96 0)
		(effects
			(font
				(size 1.27 1.27)
			)
			(justify left bottom)
		)
	)
	(label "DSICtrl.IRQ1"
		(at 255.27 205.74 0)
		(effects
			(font
				(size 1.27 1.27)
			)
			(justify left bottom)
		)
	)
	(label "HDMI.CLK_P"
		(at 229.87 63.5 0)
		(effects
			(font
				(size 1.27 1.27)
			)
			(justify left bottom)
		)
	)
	(label "DSI.D1_P"
		(at 137.16 181.61 180)
		(effects
			(font
				(size 1.27 1.27)
			)
			(justify right bottom)
		)
	)
	(label "HDMI.D0_P"
		(at 162.56 58.42 0)
		(effects
			(font
				(size 1.27 1.27)
			)
			(justify left bottom)
		)
	)
	(label "DSI.D2_P"
		(at 137.16 167.64 180)
		(effects
			(font
				(size 1.27 1.27)
			)
			(justify right bottom)
		)
	)
	(label "DSI.CLK_N"
		(at 137.16 198.12 180)
		(effects
			(font
				(size 1.27 1.27)
			)
			(justify right bottom)
		)
	)
	(label "CEC"
		(at 256.54 78.74 0)
		(effects
			(font
				(size 1.27 1.27)
			)
			(justify left bottom)
		)
	)
	(label "DSI.D2_N"
		(at 209.55 193.04 0)
		(effects
			(font
				(size 1.27 1.27)
			)
			(justify left bottom)
		)
	)
	(label "DSICtrl.~{RST}"
		(at 255.27 213.36 0)
		(effects
			(font
				(size 1.27 1.27)
			)
			(justify left bottom)
		)
	)
	(label "DSI.D3_P"
		(at 137.16 162.56 180)
		(effects
			(font
				(size 1.27 1.27)
			)
			(justify right bottom)
		)
	)
	(label "DSI.D2_P"
		(at 209.55 195.58 0)
		(effects
			(font
				(size 1.27 1.27)
			)
			(justify left bottom)
		)
	)
	(label "DSI.D1_N"
		(at 137.16 179.07 180)
		(effects
			(font
				(size 1.27 1.27)
			)
			(justify right bottom)
		)
	)
	(label "DSI.D0_N"
		(at 209.55 208.28 0)
		(effects
			(font
				(size 1.27 1.27)
			)
			(justify left bottom)
		)
	)
	(label "DSI.D3_P"
		(at 209.55 187.96 0)
		(effects
			(font
				(size 1.27 1.27)
			)
			(justify left bottom)
		)
	)
	(label "HDMI.D2_P"
		(at 229.87 40.64 0)
		(effects
			(font
				(size 1.27 1.27)
			)
			(justify left bottom)
		)
	)
	(label "HDMI.D2_N"
		(at 162.56 43.18 0)
		(effects
			(font
				(size 1.27 1.27)
			)
			(justify left bottom)
		)
	)
	(label "SDA"
		(at 252.73 73.66 180)
		(effects
			(font
				(size 1.27 1.27)
			)
			(justify right bottom)
		)
	)
	(label "DSICtrl.DIM"
		(at 125.73 246.38 0)
		(effects
			(font
				(size 1.27 1.27)
			)
			(justify left bottom)
		)
	)
	(label "DSICtrl.DIM"
		(at 255.27 215.9 0)
		(effects
			(font
				(size 1.27 1.27)
			)
			(justify left bottom)
		)
	)
	(label "CEC"
		(at 252.73 78.74 180)
		(effects
			(font
				(size 1.27 1.27)
			)
			(justify right bottom)
		)
	)
	(label "SCL"
		(at 256.54 71.12 0)
		(effects
			(font
				(size 1.27 1.27)
			)
			(justify left bottom)
		)
	)
	(label "HPD"
		(at 256.54 83.82 0)
		(effects
			(font
				(size 1.27 1.27)
			)
			(justify left bottom)
		)
	)
	(label "DSICtrl.~{RST}"
		(at 125.73 243.84 0)
		(effects
			(font
				(size 1.27 1.27)
			)
			(justify left bottom)
		)
	)
	(label "HDMI.HPD"
		(at 229.87 81.28 0)
		(effects
			(font
				(size 1.27 1.27)
			)
			(justify left bottom)
		)
	)
	(label "DSI.D1_P"
		(at 209.55 203.2 0)
		(effects
			(font
				(size 1.27 1.27)
			)
			(justify left bottom)
		)
	)
	(label "DSI.CLK_N"
		(at 209.55 215.9 0)
		(effects
			(font
				(size 1.27 1.27)
			)
			(justify left bottom)
		)
	)
	(label "HDMI.SDA"
		(at 229.87 73.66 0)
		(effects
			(font
				(size 1.27 1.27)
			)
			(justify left bottom)
		)
	)
	(label "SCL"
		(at 252.73 76.2 180)
		(effects
			(font
				(size 1.27 1.27)
			)
			(justify right bottom)
		)
	)
	(label "HDMI.D1_P"
		(at 229.87 48.26 0)
		(effects
			(font
				(size 1.27 1.27)
			)
			(justify left bottom)
		)
	)
	(label "HDMI.CLK_P"
		(at 162.56 63.5 0)
		(effects
			(font
				(size 1.27 1.27)
			)
			(justify left bottom)
		)
	)
	(label "DSI.D1_N"
		(at 209.55 200.66 0)
		(effects
			(font
				(size 1.27 1.27)
			)
			(justify left bottom)
		)
	)
	(hierarchical_label "DSI{DSI}"
		(shape input)
		(at 143.51 153.67 0)
		(effects
			(font
				(size 1.27 1.27)
			)
			(justify left)
		)
	)
	(hierarchical_label "I_{2}C1{I_{2}C}"
		(shape bidirectional)
		(at 271.78 198.12 0)
		(effects
			(font
				(size 1.27 1.27)
			)
			(justify left)
		)
	)
	(hierarchical_label "DSI{DSI}"
		(shape input)
		(at 203.2 180.34 180)
		(effects
			(font
				(size 1.27 1.27)
			)
			(justify right)
		)
	)
	(hierarchical_label "HDMI{HDMI}"
		(shape bidirectional)
		(at 226.06 36.83 180)
		(effects
			(font
				(size 1.27 1.27)
			)
			(justify right)
		)
	)
	(hierarchical_label "DSICtrl{DSICtrl}"
		(shape bidirectional)
		(at 142.24 224.79 0)
		(effects
			(font
				(size 1.27 1.27)
			)
			(justify left)
		)
	)
	(hierarchical_label "I_{2}C1{I_{2}C}"
		(shape bidirectional)
		(at 142.24 219.71 0)
		(effects
			(font
				(size 1.27 1.27)
			)
			(justify left)
		)
	)
	(hierarchical_label "HDMI{HDMI}"
		(shape bidirectional)
		(at 157.48 36.83 180)
		(effects
			(font
				(size 1.27 1.27)
			)
			(justify right)
		)
	)
	(hierarchical_label "DSICtrl{DSICtrl}"
		(shape bidirectional)
		(at 271.78 203.2 0)
		(effects
			(font
				(size 1.27 1.27)
			)
			(justify left)
		)
	)
	(symbol
		(lib_id "antmicroB2BConnectors:Socket_Molex_SlimStack_2x20_543630489")
		(at 222.25 182.88 0)
		(unit 1)
		(exclude_from_sim no)
		(in_bom yes)
		(on_board yes)
		(dnp no)
		(fields_autoplaced yes)
		(property "Reference" "J701"
			(at 227.965 175.26 0)
			(effects
				(font
					(size 1.27 1.27)
					(thickness 0.15)
				)
			)
		)
		(property "Value" "Socket_Molex_SlimStack_2x20_543630489"
			(at 247.65 187.96 0)
			(effects
				(font
					(size 1.27 1.27)
					(thickness 0.15)
				)
				(justify left bottom)
				(hide yes)
			)
		)
		(property "Footprint" "antmicro-footprints:Conn_Socket_Molex_SlimStack_2x20_543630489"
			(at 247.65 190.5 0)
			(effects
				(font
					(size 1.27 1.27)
					(thickness 0.15)
				)
				(justify left bottom)
				(hide yes)
			)
		)
		(property "Datasheet" "https://www.molex.com/pdm_docs/sd/543630489_sd.pdf"
			(at 247.65 193.04 0)
			(effects
				(font
					(size 1.27 1.27)
					(thickness 0.15)
				)
				(justify left bottom)
				(hide yes)
			)
		)
		(property "Description" ""
			(at 222.25 182.88 0)
			(effects
				(font
					(size 1.27 1.27)
				)
				(hide yes)
			)
		)
		(property "MPN" "543630489"
			(at 227.965 177.8 0)
			(effects
				(font
					(size 1.27 1.27)
					(thickness 0.15)
				)
			)
		)
		(property "Manufacturer" "Molex"
			(at 247.65 195.58 0)
			(effects
				(font
					(size 1.27 1.27)
					(thickness 0.15)
				)
				(justify left bottom)
				(hide yes)
			)
		)
		(property "Pitch" "0.5 mm"
			(at 247.65 195.58 0)
			(effects
				(font
					(size 1.27 1.27)
					(thickness 0.15)
				)
				(justify left bottom)
				(hide yes)
			)
		)
		(property "Author" "Antmicro"
			(at 247.65 200.66 0)
			(effects
				(font
					(size 1.27 1.27)
					(thickness 0.15)
				)
				(justify left bottom)
				(hide yes)
			)
		)
		(property "License" "Apache-2.0"
			(at 247.65 203.2 0)
			(effects
				(font
					(size 1.27 1.27)
					(thickness 0.15)
				)
				(justify left bottom)
				(hide yes)
			)
		)
		(pin "8"
		)
		(pin "7"
		)
		(pin "2"
		)
		(pin "9"
		)
		(pin "20"
		)
		(pin "19"
		)
		(pin "18"
		)
		(pin "5"
		)
		(pin "4"
		)
		(pin "21"
		)
		(pin "6"
		)
		(pin "29"
		)
		(pin "3"
		)
		(pin "25"
		)
		(pin "27"
		)
		(pin "23"
		)
		(pin "30"
		)
		(pin "15"
		)
		(pin "26"
		)
		(pin "28"
		)
		(pin "24"
		)
		(pin "17"
		)
		(pin "16"
		)
		(pin "13"
		)
		(pin "22"
		)
		(pin "12"
		)
		(pin "10"
		)
		(pin "11"
		)
		(pin "1"
		)
		(pin "14"
		)
		(pin "40"
		)
		(pin "37"
		)
		(pin "38"
		)
		(pin "32"
		)
		(pin "39"
		)
		(pin "31"
		)
		(pin "33"
		)
		(pin "36"
		)
		(pin "35"
		)
		(pin "34"
		)
		(pin "MP"
		)
		(instances
			(project "cm4-baseboard"
				(path ""
					(reference "J701")
					(unit 1)
				)
			)
		)
	)
	(symbol
		(lib_id "antmicroTVSDiodes:PUSB3F96X_PASS")
		(at 123.19 160.02 0)
		(mirror y)
		(unit 1)
		(exclude_from_sim no)
		(in_bom yes)
		(on_board yes)
		(dnp no)
		(fields_autoplaced yes)
		(property "Reference" "D701"
			(at 109.22 162.5599 0)
			(effects
				(font
					(size 1.27 1.27)
					(thickness 0.15)
				)
				(justify left)
			)
		)
		(property "Value" "PUSB3F96X_PASS"
			(at 97.79 167.64 0)
			(effects
				(font
					(size 1.27 1.27)
					(thickness 0.15)
				)
				(justify left bottom)
				(hide yes)
			)
		)
		(property "Footprint" "antmicro-footprints:Nexperia_DFN-10_2.5x1mm_P0.5mm"
			(at 97.79 170.18 0)
			(effects
				(font
					(size 1.27 1.27)
					(thickness 0.15)
				)
				(justify left bottom)
				(hide yes)
			)
		)
		(property "Datasheet" "https://mouser.com/datasheet/2/916/PUSB3F96-1600324.pdf"
			(at 97.79 172.72 0)
			(effects
				(font
					(size 1.27 1.27)
					(thickness 0.15)
				)
				(justify left bottom)
				(hide yes)
			)
		)
		(property "Description" ""
			(at 123.19 160.02 0)
			(effects
				(font
					(size 1.27 1.27)
				)
				(hide yes)
			)
		)
		(property "Manufacturer" "Nexperia"
			(at 97.79 175.26 0)
			(effects
				(font
					(size 1.27 1.27)
					(thickness 0.15)
				)
				(justify left bottom)
				(hide yes)
			)
		)
		(property "MPN" "PUSB3F96X"
			(at 109.22 165.0999 0)
			(effects
				(font
					(size 1.27 1.27)
					(thickness 0.15)
				)
				(justify left)
			)
		)
		(property "Author" "Antmicro"
			(at 97.79 177.8 0)
			(effects
				(font
					(size 1.27 1.27)
					(thickness 0.15)
				)
				(justify left bottom)
				(hide yes)
			)
		)
		(property "License" "Apache-2.0"
			(at 97.79 180.34 0)
			(effects
				(font
					(size 1.27 1.27)
					(thickness 0.15)
				)
				(justify left bottom)
				(hide yes)
			)
		)
		(pin "1"
		)
		(pin "10"
		)
		(pin "2"
		)
		(pin "3"
		)
		(pin "4"
		)
		(pin "5"
		)
		(pin "6"
		)
		(pin "7"
		)
		(pin "8"
		)
		(pin "9"
		)
		(instances
			(project "cm4-baseboard"
				(path ""
					(reference "D701")
					(unit 1)
				)
			)
		)
	)
	(symbol
		(lib_id "antmicropower:GND")
		(at 124.46 252.73 0)
		(mirror y)
		(unit 1)
		(exclude_from_sim no)
		(in_bom yes)
		(on_board yes)
		(dnp no)
		(fields_autoplaced yes)
		(property "Reference" "#PWR0705"
			(at 115.57 255.27 0)
			(effects
				(font
					(size 1.27 1.27)
					(thickness 0.15)
				)
				(justify left bottom)
				(hide yes)
			)
		)
		(property "Value" "GND"
			(at 124.46 257.81 0)
			(effects
				(font
					(size 1.27 1.27)
				)
			)
		)
		(property "Footprint" ""
			(at 115.57 260.35 0)
			(effects
				(font
					(size 1.27 1.27)
					(thickness 0.15)
				)
				(justify left bottom)
				(hide yes)
			)
		)
		(property "Datasheet" ""
			(at 115.57 265.43 0)
			(effects
				(font
					(size 1.27 1.27)
					(thickness 0.15)
				)
				(justify left bottom)
				(hide yes)
			)
		)
		(property "Description" ""
			(at 124.46 252.73 0)
			(effects
				(font
					(size 1.27 1.27)
				)
				(hide yes)
			)
		)
		(property "Author" "Antmicro"
			(at 115.57 260.35 0)
			(effects
				(font
					(size 1.27 1.27)
					(thickness 0.15)
				)
				(justify left bottom)
				(hide yes)
			)
		)
		(property "License" "Apache-2.0"
			(at 115.57 262.89 0)
			(effects
				(font
					(size 1.27 1.27)
					(thickness 0.15)
				)
				(justify left bottom)
				(hide yes)
			)
		)
		(pin "1"
		)
		(instances
			(project "cm4-baseboard"
				(path ""
					(reference "#PWR0705")
					(unit 1)
				)
			)
		)
	)
	(symbol
		(lib_id "antmicropower:GND")
		(at 176.53 69.85 0)
		(unit 1)
		(exclude_from_sim no)
		(in_bom yes)
		(on_board yes)
		(dnp no)
		(property "Reference" "#PWR0707"
			(at 185.42 72.39 0)
			(effects
				(font
					(size 1.27 1.27)
					(thickness 0.15)
				)
				(justify left bottom)
				(hide yes)
			)
		)
		(property "Value" "GND"
			(at 176.53 73.66 0)
			(effects
				(font
					(size 1.27 1.27)
				)
			)
		)
		(property "Footprint" ""
			(at 185.42 77.47 0)
			(effects
				(font
					(size 1.27 1.27)
					(thickness 0.15)
				)
				(justify left bottom)
				(hide yes)
			)
		)
		(property "Datasheet" ""
			(at 185.42 82.55 0)
			(effects
				(font
					(size 1.27 1.27)
					(thickness 0.15)
				)
				(justify left bottom)
				(hide yes)
			)
		)
		(property "Description" ""
			(at 176.53 69.85 0)
			(effects
				(font
					(size 1.27 1.27)
				)
				(hide yes)
			)
		)
		(property "Author" "Antmicro"
			(at 185.42 77.47 0)
			(effects
				(font
					(size 1.27 1.27)
					(thickness 0.15)
				)
				(justify left bottom)
				(hide yes)
			)
		)
		(property "License" "Apache-2.0"
			(at 185.42 80.01 0)
			(effects
				(font
					(size 1.27 1.27)
					(thickness 0.15)
				)
				(justify left bottom)
				(hide yes)
			)
		)
		(pin "1"
		)
		(instances
			(project "cm4-baseboard"
				(path ""
					(reference "#PWR0707")
					(unit 1)
				)
			)
		)
	)
	(symbol
		(lib_id "antmicropower:GND")
		(at 255.27 102.87 0)
		(unit 1)
		(exclude_from_sim no)
		(in_bom yes)
		(on_board yes)
		(dnp no)
		(fields_autoplaced yes)
		(property "Reference" "#PWR03"
			(at 264.16 105.41 0)
			(effects
				(font
					(size 1.27 1.27)
					(thickness 0.15)
				)
				(justify left bottom)
				(hide yes)
			)
		)
		(property "Value" "GND"
			(at 253.2598 107.95 0)
			(effects
				(font
					(size 1.27 1.27)
					(thickness 0.15)
				)
				(justify left bottom)
			)
		)
		(property "Footprint" ""
			(at 264.16 110.49 0)
			(effects
				(font
					(size 1.27 1.27)
					(thickness 0.15)
				)
				(justify left bottom)
				(hide yes)
			)
		)
		(property "Datasheet" ""
			(at 264.16 115.57 0)
			(effects
				(font
					(size 1.27 1.27)
					(thickness 0.15)
				)
				(justify left bottom)
				(hide yes)
			)
		)
		(property "Description" ""
			(at 255.27 102.87 0)
			(effects
				(font
					(size 1.27 1.27)
				)
				(hide yes)
			)
		)
		(property "Author" "Antmicro"
			(at 264.16 110.49 0)
			(effects
				(font
					(size 1.27 1.27)
					(thickness 0.15)
				)
				(justify left bottom)
				(hide yes)
			)
		)
		(property "License" "Apache-2.0"
			(at 264.16 113.03 0)
			(effects
				(font
					(size 1.27 1.27)
					(thickness 0.15)
				)
				(justify left bottom)
				(hide yes)
			)
		)
		(pin "1"
		)
		(instances
			(project "cm4-baseboard"
				(path ""
					(reference "#PWR03")
					(unit 1)
				)
			)
		)
	)
	(symbol
		(lib_id "antmicropower:GND")
		(at 285.75 179.07 0)
		(mirror y)
		(unit 1)
		(exclude_from_sim no)
		(in_bom yes)
		(on_board yes)
		(dnp no)
		(fields_autoplaced yes)
		(property "Reference" "#PWR0718"
			(at 285.75 185.42 0)
			(effects
				(font
					(size 1.27 1.27)
				)
				(justify left bottom)
				(hide yes)
			)
		)
		(property "Value" "GND"
			(at 285.75 182.88 0)
			(effects
				(font
					(size 1.27 1.27)
				)
			)
		)
		(property "Footprint" ""
			(at 285.75 179.07 0)
			(effects
				(font
					(size 1.27 1.27)
				)
				(hide yes)
			)
		)
		(property "Datasheet" ""
			(at 285.75 179.07 0)
			(effects
				(font
					(size 1.27 1.27)
				)
				(hide yes)
			)
		)
		(property "Description" ""
			(at 285.75 179.07 0)
			(effects
				(font
					(size 1.27 1.27)
				)
				(hide yes)
			)
		)
		(property "Author" "Antmicro"
			(at 276.86 186.69 0)
			(effects
				(font
					(size 1.27 1.27)
					(thickness 0.15)
				)
				(justify left bottom)
				(hide yes)
			)
		)
		(property "License" "Apache-2.0"
			(at 276.86 189.23 0)
			(effects
				(font
					(size 1.27 1.27)
					(thickness 0.15)
				)
				(justify left bottom)
				(hide yes)
			)
		)
		(pin "1"
		)
		(instances
			(project "cm4-baseboard"
				(path ""
					(reference "#PWR0718")
					(unit 1)
				)
			)
		)
	)
	(symbol
		(lib_id "antmicropower:GND")
		(at 220.98 236.22 0)
		(unit 1)
		(exclude_from_sim no)
		(in_bom yes)
		(on_board yes)
		(dnp no)
		(fields_autoplaced yes)
		(property "Reference" "#PWR0709"
			(at 229.87 238.76 0)
			(effects
				(font
					(size 1.27 1.27)
					(thickness 0.15)
				)
				(justify left bottom)
				(hide yes)
			)
		)
		(property "Value" "GND"
			(at 220.98 241.3 0)
			(effects
				(font
					(size 1.27 1.27)
					(thickness 0.15)
				)
			)
		)
		(property "Footprint" ""
			(at 229.87 243.84 0)
			(effects
				(font
					(size 1.27 1.27)
					(thickness 0.15)
				)
				(justify left bottom)
				(hide yes)
			)
		)
		(property "Datasheet" ""
			(at 229.87 248.92 0)
			(effects
				(font
					(size 1.27 1.27)
					(thickness 0.15)
				)
				(justify left bottom)
				(hide yes)
			)
		)
		(property "Description" ""
			(at 220.98 236.22 0)
			(effects
				(font
					(size 1.27 1.27)
				)
				(hide yes)
			)
		)
		(property "Author" "Antmicro"
			(at 229.87 243.84 0)
			(effects
				(font
					(size 1.27 1.27)
					(thickness 0.15)
				)
				(justify left bottom)
				(hide yes)
			)
		)
		(property "License" "Apache-2.0"
			(at 229.87 246.38 0)
			(effects
				(font
					(size 1.27 1.27)
					(thickness 0.15)
				)
				(justify left bottom)
				(hide yes)
			)
		)
		(pin "1"
		)
		(instances
			(project "cm4-baseboard"
				(path ""
					(reference "#PWR0709")
					(unit 1)
				)
			)
		)
	)
	(symbol
		(lib_id "antmicroTVSDiodes:PESD5Z5_0F")
		(at 255.27 95.25 90)
		(mirror x)
		(unit 1)
		(exclude_from_sim no)
		(in_bom yes)
		(on_board yes)
		(dnp no)
		(fields_autoplaced yes)
		(property "Reference" "D712"
			(at 257.81 96.52 90)
			(effects
				(font
					(size 1.27 1.27)
					(thickness 0.15)
				)
				(justify right)
			)
		)
		(property "Value" "PESD5Z5_0F"
			(at 257.81 98.1075 90)
			(effects
				(font
					(size 1.27 1.27)
					(thickness 0.15)
				)
				(justify right)
				(hide yes)
			)
		)
		(property "Footprint" "antmicro-footprints:SOD-523"
			(at 260.35 110.49 0)
			(effects
				(font
					(size 1.27 1.27)
					(thickness 0.15)
				)
				(justify left bottom)
				(hide yes)
			)
		)
		(property "Datasheet" "https://assets.nexperia.com/documents/data-sheet/PESD5Z5_0.pdf"
			(at 262.89 110.49 0)
			(effects
				(font
					(size 1.27 1.27)
					(thickness 0.15)
				)
				(justify left bottom)
				(hide yes)
			)
		)
		(property "Description" ""
			(at 255.27 95.25 0)
			(effects
				(font
					(size 1.27 1.27)
				)
				(hide yes)
			)
		)
		(property "Manufacturer" "Nexperia"
			(at 265.43 110.49 0)
			(effects
				(font
					(size 1.27 1.27)
					(thickness 0.15)
				)
				(justify left bottom)
				(hide yes)
			)
		)
		(property "MPN" "PESD5Z5.0F"
			(at 257.81 99.06 90)
			(effects
				(font
					(size 1.27 1.27)
					(thickness 0.15)
				)
				(justify right)
			)
		)
		(property "Author" "Antmicro"
			(at 270.51 110.49 0)
			(effects
				(font
					(size 1.27 1.27)
					(thickness 0.15)
				)
				(justify left bottom)
				(hide yes)
			)
		)
		(property "License" "Apache-2.0"
			(at 273.05 110.49 0)
			(effects
				(font
					(size 1.27 1.27)
					(thickness 0.15)
				)
				(justify left bottom)
				(hide yes)
			)
		)
		(pin "2"
		)
		(pin "1"
		)
		(instances
			(project "cm4-baseboard"
				(path ""
					(reference "D712")
					(unit 1)
				)
			)
		)
	)
	(symbol
		(lib_id "antmicropower:GND")
		(at 124.46 171.45 0)
		(mirror y)
		(unit 1)
		(exclude_from_sim no)
		(in_bom yes)
		(on_board yes)
		(dnp no)
		(fields_autoplaced yes)
		(property "Reference" "#PWR0701"
			(at 115.57 173.99 0)
			(effects
				(font
					(size 1.27 1.27)
					(thickness 0.15)
				)
				(justify left bottom)
				(hide yes)
			)
		)
		(property "Value" "GND"
			(at 124.46 176.53 0)
			(effects
				(font
					(size 1.27 1.27)
				)
			)
		)
		(property "Footprint" ""
			(at 115.57 179.07 0)
			(effects
				(font
					(size 1.27 1.27)
					(thickness 0.15)
				)
				(justify left bottom)
				(hide yes)
			)
		)
		(property "Datasheet" ""
			(at 115.57 184.15 0)
			(effects
				(font
					(size 1.27 1.27)
					(thickness 0.15)
				)
				(justify left bottom)
				(hide yes)
			)
		)
		(property "Description" ""
			(at 124.46 171.45 0)
			(effects
				(font
					(size 1.27 1.27)
				)
				(hide yes)
			)
		)
		(property "Author" "Antmicro"
			(at 115.57 179.07 0)
			(effects
				(font
					(size 1.27 1.27)
					(thickness 0.15)
				)
				(justify left bottom)
				(hide yes)
			)
		)
		(property "License" "Apache-2.0"
			(at 115.57 181.61 0)
			(effects
				(font
					(size 1.27 1.27)
					(thickness 0.15)
				)
				(justify left bottom)
				(hide yes)
			)
		)
		(pin "1"
		)
		(instances
			(project "cm4-baseboard"
				(path ""
					(reference "#PWR0701")
					(unit 1)
				)
			)
		)
	)
	(symbol
		(lib_id "antmicroTVSDiodes:PUSB3F96X_PASS")
		(at 177.8 40.64 0)
		(unit 1)
		(exclude_from_sim no)
		(in_bom yes)
		(on_board yes)
		(dnp no)
		(fields_autoplaced yes)
		(property "Reference" "D706"
			(at 191.77 44.4499 0)
			(effects
				(font
					(size 1.27 1.27)
					(thickness 0.15)
				)
				(justify left)
			)
		)
		(property "Value" "PUSB3F96X_PASS"
			(at 203.2 48.26 0)
			(effects
				(font
					(size 1.27 1.27)
					(thickness 0.15)
				)
				(justify left bottom)
				(hide yes)
			)
		)
		(property "Footprint" "antmicro-footprints:Nexperia_DFN-10_2.5x1mm_P0.5mm"
			(at 203.2 50.8 0)
			(effects
				(font
					(size 1.27 1.27)
					(thickness 0.15)
				)
				(justify left bottom)
				(hide yes)
			)
		)
		(property "Datasheet" "https://mouser.com/datasheet/2/916/PUSB3F96-1600324.pdf"
			(at 203.2 53.34 0)
			(effects
				(font
					(size 1.27 1.27)
					(thickness 0.15)
				)
				(justify left bottom)
				(hide yes)
			)
		)
		(property "Description" ""
			(at 177.8 40.64 0)
			(effects
				(font
					(size 1.27 1.27)
				)
				(hide yes)
			)
		)
		(property "Manufacturer" "Nexperia"
			(at 203.2 55.88 0)
			(effects
				(font
					(size 1.27 1.27)
					(thickness 0.15)
				)
				(justify left bottom)
				(hide yes)
			)
		)
		(property "MPN" "PUSB3F96X"
			(at 191.77 46.9899 0)
			(effects
				(font
					(size 1.27 1.27)
					(thickness 0.15)
				)
				(justify left)
			)
		)
		(property "Author" "Antmicro"
			(at 203.2 58.42 0)
			(effects
				(font
					(size 1.27 1.27)
					(thickness 0.15)
				)
				(justify left bottom)
				(hide yes)
			)
		)
		(property "License" "Apache-2.0"
			(at 203.2 60.96 0)
			(effects
				(font
					(size 1.27 1.27)
					(thickness 0.15)
				)
				(justify left bottom)
				(hide yes)
			)
		)
		(pin "1"
		)
		(pin "10"
		)
		(pin "2"
		)
		(pin "3"
		)
		(pin "4"
		)
		(pin "5"
		)
		(pin "6"
		)
		(pin "7"
		)
		(pin "8"
		)
		(pin "9"
		)
		(instances
			(project "cm4-baseboard"
				(path ""
					(reference "D706")
					(unit 1)
				)
			)
		)
	)
	(symbol
		(lib_id "antmicropower:GND")
		(at 176.53 87.63 0)
		(unit 1)
		(exclude_from_sim no)
		(in_bom yes)
		(on_board yes)
		(dnp no)
		(property "Reference" "#PWR0708"
			(at 185.42 90.17 0)
			(effects
				(font
					(size 1.27 1.27)
					(thickness 0.15)
				)
				(justify left bottom)
				(hide yes)
			)
		)
		(property "Value" "GND"
			(at 176.53 91.44 0)
			(effects
				(font
					(size 1.27 1.27)
				)
			)
		)
		(property "Footprint" ""
			(at 185.42 95.25 0)
			(effects
				(font
					(size 1.27 1.27)
					(thickness 0.15)
				)
				(justify left bottom)
				(hide yes)
			)
		)
		(property "Datasheet" ""
			(at 185.42 100.33 0)
			(effects
				(font
					(size 1.27 1.27)
					(thickness 0.15)
				)
				(justify left bottom)
				(hide yes)
			)
		)
		(property "Description" ""
			(at 176.53 87.63 0)
			(effects
				(font
					(size 1.27 1.27)
				)
				(hide yes)
			)
		)
		(property "Author" "Antmicro"
			(at 185.42 95.25 0)
			(effects
				(font
					(size 1.27 1.27)
					(thickness 0.15)
				)
				(justify left bottom)
				(hide yes)
			)
		)
		(property "License" "Apache-2.0"
			(at 185.42 97.79 0)
			(effects
				(font
					(size 1.27 1.27)
					(thickness 0.15)
				)
				(justify left bottom)
				(hide yes)
			)
		)
		(pin "1"
		)
		(instances
			(project "cm4-baseboard"
				(path ""
					(reference "#PWR0708")
					(unit 1)
				)
			)
		)
	)
	(symbol
		(lib_id "antmicroTVSDiodes:PUSB3F96X_PASS")
		(at 177.8 76.2 0)
		(unit 1)
		(exclude_from_sim no)
		(in_bom yes)
		(on_board yes)
		(dnp no)
		(fields_autoplaced yes)
		(property "Reference" "D708"
			(at 191.77 80.0099 0)
			(effects
				(font
					(size 1.27 1.27)
					(thickness 0.15)
				)
				(justify left)
			)
		)
		(property "Value" "PUSB3F96X_PASS"
			(at 203.2 83.82 0)
			(effects
				(font
					(size 1.27 1.27)
					(thickness 0.15)
				)
				(justify left bottom)
				(hide yes)
			)
		)
		(property "Footprint" "antmicro-footprints:Nexperia_DFN-10_2.5x1mm_P0.5mm"
			(at 203.2 86.36 0)
			(effects
				(font
					(size 1.27 1.27)
					(thickness 0.15)
				)
				(justify left bottom)
				(hide yes)
			)
		)
		(property "Datasheet" "https://mouser.com/datasheet/2/916/PUSB3F96-1600324.pdf"
			(at 203.2 88.9 0)
			(effects
				(font
					(size 1.27 1.27)
					(thickness 0.15)
				)
				(justify left bottom)
				(hide yes)
			)
		)
		(property "Description" ""
			(at 177.8 76.2 0)
			(effects
				(font
					(size 1.27 1.27)
				)
				(hide yes)
			)
		)
		(property "Manufacturer" "Nexperia"
			(at 203.2 91.44 0)
			(effects
				(font
					(size 1.27 1.27)
					(thickness 0.15)
				)
				(justify left bottom)
				(hide yes)
			)
		)
		(property "MPN" "PUSB3F96X"
			(at 191.77 82.5499 0)
			(effects
				(font
					(size 1.27 1.27)
					(thickness 0.15)
				)
				(justify left)
			)
		)
		(property "Author" "Antmicro"
			(at 203.2 93.98 0)
			(effects
				(font
					(size 1.27 1.27)
					(thickness 0.15)
				)
				(justify left bottom)
				(hide yes)
			)
		)
		(property "License" "Apache-2.0"
			(at 203.2 96.52 0)
			(effects
				(font
					(size 1.27 1.27)
					(thickness 0.15)
				)
				(justify left bottom)
				(hide yes)
			)
		)
		(pin "1"
		)
		(pin "10"
		)
		(pin "2"
		)
		(pin "3"
		)
		(pin "4"
		)
		(pin "5"
		)
		(pin "6"
		)
		(pin "7"
		)
		(pin "8"
		)
		(pin "9"
		)
		(instances
			(project "cm4-baseboard"
				(path ""
					(reference "D708")
					(unit 1)
				)
			)
		)
	)
	(symbol
		(lib_id "antmicropower:+3V3")
		(at 285.75 171.45 0)
		(unit 1)
		(exclude_from_sim no)
		(in_bom yes)
		(on_board yes)
		(dnp no)
		(property "Reference" "#PWR0717"
			(at 300.99 171.45 0)
			(effects
				(font
					(size 1.27 1.27)
					(thickness 0.15)
				)
				(justify left bottom)
				(hide yes)
			)
		)
		(property "Value" "+3V3"
			(at 285.75 167.64 0)
			(effects
				(font
					(size 1.27 1.27)
					(thickness 0.15)
				)
			)
		)
		(property "Footprint" ""
			(at 300.99 179.07 0)
			(effects
				(font
					(size 1.27 1.27)
					(thickness 0.15)
				)
				(justify left bottom)
				(hide yes)
			)
		)
		(property "Datasheet" ""
			(at 300.99 181.61 0)
			(effects
				(font
					(size 1.27 1.27)
					(thickness 0.15)
				)
				(justify left bottom)
				(hide yes)
			)
		)
		(property "Description" ""
			(at 285.75 171.45 0)
			(effects
				(font
					(size 1.27 1.27)
				)
				(hide yes)
			)
		)
		(property "Author" "Antmicro"
			(at 300.99 173.99 0)
			(effects
				(font
					(size 1.27 1.27)
					(thickness 0.15)
				)
				(justify left bottom)
				(hide yes)
			)
		)
		(property "License" "Apache-2.0"
			(at 300.99 176.53 0)
			(effects
				(font
					(size 1.27 1.27)
					(thickness 0.15)
				)
				(justify left bottom)
				(hide yes)
			)
		)
		(pin "1"
		)
		(instances
			(project "cm4-baseboard"
				(path ""
					(reference "#PWR0717")
					(unit 1)
				)
			)
		)
	)
	(symbol
		(lib_id "antmicropower:GND")
		(at 259.08 181.61 0)
		(mirror y)
		(unit 1)
		(exclude_from_sim no)
		(in_bom yes)
		(on_board yes)
		(dnp no)
		(fields_autoplaced yes)
		(property "Reference" "#PWR0713"
			(at 259.08 187.96 0)
			(effects
				(font
					(size 1.27 1.27)
				)
				(justify left bottom)
				(hide yes)
			)
		)
		(property "Value" "GND"
			(at 259.08 185.42 0)
			(effects
				(font
					(size 1.27 1.27)
				)
			)
		)
		(property "Footprint" ""
			(at 259.08 181.61 0)
			(effects
				(font
					(size 1.27 1.27)
				)
				(hide yes)
			)
		)
		(property "Datasheet" ""
			(at 259.08 181.61 0)
			(effects
				(font
					(size 1.27 1.27)
				)
				(hide yes)
			)
		)
		(property "Description" ""
			(at 259.08 181.61 0)
			(effects
				(font
					(size 1.27 1.27)
				)
				(hide yes)
			)
		)
		(property "Author" "Antmicro"
			(at 250.19 189.23 0)
			(effects
				(font
					(size 1.27 1.27)
					(thickness 0.15)
				)
				(justify left bottom)
				(hide yes)
			)
		)
		(property "License" "Apache-2.0"
			(at 250.19 191.77 0)
			(effects
				(font
					(size 1.27 1.27)
					(thickness 0.15)
				)
				(justify left bottom)
				(hide yes)
			)
		)
		(pin "1"
		)
		(instances
			(project "cm4-baseboard"
				(path ""
					(reference "#PWR0713")
					(unit 1)
				)
			)
		)
	)
	(symbol
		(lib_id "antmicropower:GND")
		(at 124.46 209.55 0)
		(mirror y)
		(unit 1)
		(exclude_from_sim no)
		(in_bom yes)
		(on_board yes)
		(dnp no)
		(fields_autoplaced yes)
		(property "Reference" "#PWR0703"
			(at 115.57 212.09 0)
			(effects
				(font
					(size 1.27 1.27)
					(thickness 0.15)
				)
				(justify left bottom)
				(hide yes)
			)
		)
		(property "Value" "GND"
			(at 124.46 214.63 0)
			(effects
				(font
					(size 1.27 1.27)
				)
			)
		)
		(property "Footprint" ""
			(at 115.57 217.17 0)
			(effects
				(font
					(size 1.27 1.27)
					(thickness 0.15)
				)
				(justify left bottom)
				(hide yes)
			)
		)
		(property "Datasheet" ""
			(at 115.57 222.25 0)
			(effects
				(font
					(size 1.27 1.27)
					(thickness 0.15)
				)
				(justify left bottom)
				(hide yes)
			)
		)
		(property "Description" ""
			(at 124.46 209.55 0)
			(effects
				(font
					(size 1.27 1.27)
				)
				(hide yes)
			)
		)
		(property "Author" "Antmicro"
			(at 115.57 217.17 0)
			(effects
				(font
					(size 1.27 1.27)
					(thickness 0.15)
				)
				(justify left bottom)
				(hide yes)
			)
		)
		(property "License" "Apache-2.0"
			(at 115.57 219.71 0)
			(effects
				(font
					(size 1.27 1.27)
					(thickness 0.15)
				)
				(justify left bottom)
				(hide yes)
			)
		)
		(pin "1"
		)
		(instances
			(project "cm4-baseboard"
				(path ""
					(reference "#PWR0703")
					(unit 1)
				)
			)
		)
	)
	(symbol
		(lib_id "antmicropower:GND")
		(at 176.53 52.07 0)
		(unit 1)
		(exclude_from_sim no)
		(in_bom yes)
		(on_board yes)
		(dnp no)
		(property "Reference" "#PWR0706"
			(at 185.42 54.61 0)
			(effects
				(font
					(size 1.27 1.27)
					(thickness 0.15)
				)
				(justify left bottom)
				(hide yes)
			)
		)
		(property "Value" "GND"
			(at 176.53 55.88 0)
			(effects
				(font
					(size 1.27 1.27)
				)
			)
		)
		(property "Footprint" ""
			(at 185.42 59.69 0)
			(effects
				(font
					(size 1.27 1.27)
					(thickness 0.15)
				)
				(justify left bottom)
				(hide yes)
			)
		)
		(property "Datasheet" ""
			(at 185.42 64.77 0)
			(effects
				(font
					(size 1.27 1.27)
					(thickness 0.15)
				)
				(justify left bottom)
				(hide yes)
			)
		)
		(property "Description" ""
			(at 176.53 52.07 0)
			(effects
				(font
					(size 1.27 1.27)
				)
				(hide yes)
			)
		)
		(property "Author" "Antmicro"
			(at 185.42 59.69 0)
			(effects
				(font
					(size 1.27 1.27)
					(thickness 0.15)
				)
				(justify left bottom)
				(hide yes)
			)
		)
		(property "License" "Apache-2.0"
			(at 185.42 62.23 0)
			(effects
				(font
					(size 1.27 1.27)
					(thickness 0.15)
				)
				(justify left bottom)
				(hide yes)
			)
		)
		(pin "1"
		)
		(instances
			(project "cm4-baseboard"
				(path ""
					(reference "#PWR0706")
					(unit 1)
				)
			)
		)
	)
	(symbol
		(lib_id "antmicropower:GND")
		(at 247.65 259.08 0)
		(mirror y)
		(unit 1)
		(exclude_from_sim no)
		(in_bom yes)
		(on_board yes)
		(dnp no)
		(fields_autoplaced yes)
		(property "Reference" "#PWR0722"
			(at 238.76 261.62 0)
			(effects
				(font
					(size 1.27 1.27)
					(thickness 0.15)
				)
				(justify left bottom)
				(hide yes)
			)
		)
		(property "Value" "GND"
			(at 249.6602 264.16 0)
			(effects
				(font
					(size 1.27 1.27)
					(thickness 0.15)
				)
				(justify left bottom)
			)
		)
		(property "Footprint" ""
			(at 238.76 266.7 0)
			(effects
				(font
					(size 1.27 1.27)
					(thickness 0.15)
				)
				(justify left bottom)
				(hide yes)
			)
		)
		(property "Datasheet" ""
			(at 238.76 271.78 0)
			(effects
				(font
					(size 1.27 1.27)
					(thickness 0.15)
				)
				(justify left bottom)
				(hide yes)
			)
		)
		(property "Description" ""
			(at 247.65 259.08 0)
			(effects
				(font
					(size 1.27 1.27)
				)
				(hide yes)
			)
		)
		(property "Author" "Antmicro"
			(at 238.76 266.7 0)
			(effects
				(font
					(size 1.27 1.27)
					(thickness 0.15)
				)
				(justify left bottom)
				(hide yes)
			)
		)
		(property "License" "Apache-2.0"
			(at 238.76 269.24 0)
			(effects
				(font
					(size 1.27 1.27)
					(thickness 0.15)
				)
				(justify left bottom)
				(hide yes)
			)
		)
		(pin "1"
		)
		(instances
			(project "cm4-baseboard"
				(path ""
					(reference "#PWR0722")
					(unit 1)
				)
			)
		)
	)
	(symbol
		(lib_id "antmicropower:+5V")
		(at 273.05 171.45 0)
		(mirror y)
		(unit 1)
		(exclude_from_sim no)
		(in_bom yes)
		(on_board yes)
		(dnp no)
		(property "Reference" "#PWR0716"
			(at 273.05 175.26 0)
			(effects
				(font
					(size 1.27 1.27)
				)
				(justify left bottom)
				(hide yes)
			)
		)
		(property "Value" "+5V"
			(at 274.32 167.64 0)
			(effects
				(font
					(size 1.27 1.27)
				)
			)
		)
		(property "Footprint" ""
			(at 273.05 171.45 0)
			(effects
				(font
					(size 1.27 1.27)
				)
				(hide yes)
			)
		)
		(property "Datasheet" ""
			(at 273.05 171.45 0)
			(effects
				(font
					(size 1.27 1.27)
				)
				(hide yes)
			)
		)
		(property "Description" ""
			(at 273.05 171.45 0)
			(effects
				(font
					(size 1.27 1.27)
				)
				(hide yes)
			)
		)
		(property "Author" "Antmicro"
			(at 257.81 179.07 0)
			(effects
				(font
					(size 1.27 1.27)
					(thickness 0.15)
				)
				(justify left bottom)
				(hide yes)
			)
		)
		(property "License" "Apache-2.0"
			(at 257.81 181.61 0)
			(effects
				(font
					(size 1.27 1.27)
					(thickness 0.15)
				)
				(justify left bottom)
				(hide yes)
			)
		)
		(pin "1"
		)
		(instances
			(project "cm4-baseboard"
				(path ""
					(reference "#PWR0716")
					(unit 1)
				)
			)
		)
	)
	(symbol
		(lib_id "antmicropower:GND")
		(at 290.83 179.07 0)
		(mirror y)
		(unit 1)
		(exclude_from_sim no)
		(in_bom yes)
		(on_board yes)
		(dnp no)
		(fields_autoplaced yes)
		(property "Reference" "#PWR0720"
			(at 290.83 185.42 0)
			(effects
				(font
					(size 1.27 1.27)
				)
				(justify left bottom)
				(hide yes)
			)
		)
		(property "Value" "GND"
			(at 290.83 182.88 0)
			(effects
				(font
					(size 1.27 1.27)
				)
			)
		)
		(property "Footprint" ""
			(at 290.83 179.07 0)
			(effects
				(font
					(size 1.27 1.27)
				)
				(hide yes)
			)
		)
		(property "Datasheet" ""
			(at 290.83 179.07 0)
			(effects
				(font
					(size 1.27 1.27)
				)
				(hide yes)
			)
		)
		(property "Description" ""
			(at 290.83 179.07 0)
			(effects
				(font
					(size 1.27 1.27)
				)
				(hide yes)
			)
		)
		(property "Author" "Antmicro"
			(at 281.94 186.69 0)
			(effects
				(font
					(size 1.27 1.27)
					(thickness 0.15)
				)
				(justify left bottom)
				(hide yes)
			)
		)
		(property "License" "Apache-2.0"
			(at 281.94 189.23 0)
			(effects
				(font
					(size 1.27 1.27)
					(thickness 0.15)
				)
				(justify left bottom)
				(hide yes)
			)
		)
		(pin "1"
		)
		(instances
			(project "cm4-baseboard"
				(path ""
					(reference "#PWR0720")
					(unit 1)
				)
			)
		)
	)
	(symbol
		(lib_id "antmicroTVSDiodes:TPD1E0B04_XDFN-2")
		(at 290.83 177.8 270)
		(mirror x)
		(unit 1)
		(exclude_from_sim no)
		(in_bom yes)
		(on_board yes)
		(dnp no)
		(fields_autoplaced yes)
		(property "Reference" "D711"
			(at 293.37 173.99 90)
			(effects
				(font
					(size 1.27 1.27)
				)
				(justify left)
			)
		)
		(property "Value" "TPD1E0B04_XDFN-2"
			(at 293.37 176.5299 90)
			(effects
				(font
					(size 1.27 1.27)
				)
				(justify left)
				(hide yes)
			)
		)
		(property "Footprint" "antmicro-footprints:XDFN-2_1x0.60mm"
			(at 295.91 172.72 0)
			(effects
				(font
					(size 1.524 1.524)
				)
				(justify left bottom)
				(hide yes)
			)
		)
		(property "Datasheet" "https://www.ti.com/general/docs/suppproductinfo.tsp?distId=26&gotoUrl=https://www.ti.com/lit/gpn/tpd1e0b04"
			(at 298.45 172.72 0)
			(effects
				(font
					(size 1.524 1.524)
				)
				(justify left bottom)
				(hide yes)
			)
		)
		(property "Description" ""
			(at 290.83 177.8 0)
			(effects
				(font
					(size 1.27 1.27)
				)
				(hide yes)
			)
		)
		(property "Manufacturer" "Texas Instruments"
			(at 318.77 172.72 0)
			(effects
				(font
					(size 1.524 1.524)
				)
				(justify left bottom)
				(hide yes)
			)
		)
		(property "MPN" "TPD1E0B04DPYR"
			(at 293.37 176.53 90)
			(effects
				(font
					(size 1.524 1.524)
				)
				(justify left)
			)
		)
		(property "Author" "Antmicro"
			(at 275.59 162.56 0)
			(effects
				(font
					(size 1.27 1.27)
					(thickness 0.15)
				)
				(justify left bottom)
				(hide yes)
			)
		)
		(property "License" "Apache-2.0"
			(at 273.05 162.56 0)
			(effects
				(font
					(size 1.27 1.27)
					(thickness 0.15)
				)
				(justify left bottom)
				(hide yes)
			)
		)
		(pin "1"
		)
		(pin "2"
		)
		(instances
			(project "cm4-baseboard"
				(path ""
					(reference "D711")
					(unit 1)
				)
			)
		)
	)
	(symbol
		(lib_id "antmicroResistorNetworksArrays:R_4x100R_0402_array")
		(at 243.84 210.82 0)
		(unit 1)
		(exclude_from_sim no)
		(in_bom yes)
		(on_board yes)
		(dnp no)
		(fields_autoplaced yes)
		(property "Reference" "R706"
			(at 248.92 222.25 0)
			(effects
				(font
					(size 1.27 1.27)
					(thickness 0.15)
				)
			)
		)
		(property "Value" "R_4x100R_0402_array"
			(at 270.51 215.9 0)
			(effects
				(font
					(size 1.27 1.27)
					(thickness 0.15)
				)
				(justify left bottom)
				(hide yes)
			)
		)
		(property "Footprint" "antmicro-footprints:R_Array_4x0402_Panasonic_EXB28V"
			(at 270.51 220.98 0)
			(effects
				(font
					(size 1.27 1.27)
					(thickness 0.15)
				)
				(justify left bottom)
				(hide yes)
			)
		)
		(property "Datasheet" "http://industrial.panasonic.com/cdbs/www-data/pdf/AOC0000/AOC0000C14.pdf"
			(at 270.51 223.52 0)
			(effects
				(font
					(size 1.27 1.27)
					(thickness 0.15)
				)
				(justify left bottom)
				(hide yes)
			)
		)
		(property "Description" ""
			(at 243.84 210.82 0)
			(effects
				(font
					(size 1.27 1.27)
				)
				(hide yes)
			)
		)
		(property "MPN" "EXB-28V101JX"
			(at 270.51 226.06 0)
			(effects
				(font
					(size 1.27 1.27)
					(thickness 0.15)
				)
				(justify left bottom)
				(hide yes)
			)
		)
		(property "Manufacturer" "Panasonic"
			(at 270.51 228.6 0)
			(effects
				(font
					(size 1.27 1.27)
					(thickness 0.15)
				)
				(justify left bottom)
				(hide yes)
			)
		)
		(property "Author" "Antmicro"
			(at 270.51 231.14 0)
			(effects
				(font
					(size 1.27 1.27)
					(thickness 0.15)
				)
				(justify left bottom)
				(hide yes)
			)
		)
		(property "License" "Apache-2.0"
			(at 270.51 233.68 0)
			(effects
				(font
					(size 1.27 1.27)
					(thickness 0.15)
				)
				(justify left bottom)
				(hide yes)
			)
		)
		(property "Val" "R_4x100R_0402"
			(at 248.92 224.79 0)
			(effects
				(font
					(size 1.27 1.27)
				)
			)
		)
		(pin "8"
		)
		(pin "4"
		)
		(pin "6"
		)
		(pin "3"
		)
		(pin "5"
		)
		(pin "7"
		)
		(pin "2"
		)
		(pin "1"
		)
		(instances
			(project "cm4-baseboard"
				(path ""
					(reference "R706")
					(unit 1)
				)
			)
		)
	)
	(symbol
		(lib_id "antmicropower:GND")
		(at 287.02 92.71 0)
		(mirror y)
		(unit 1)
		(exclude_from_sim no)
		(in_bom yes)
		(on_board yes)
		(dnp no)
		(fields_autoplaced yes)
		(property "Reference" "#PWR0721"
			(at 287.02 99.06 0)
			(effects
				(font
					(size 1.27 1.27)
				)
				(justify left bottom)
				(hide yes)
			)
		)
		(property "Value" "GND"
			(at 287.02 96.52 0)
			(effects
				(font
					(size 1.27 1.27)
				)
			)
		)
		(property "Footprint" ""
			(at 287.02 92.71 0)
			(effects
				(font
					(size 1.27 1.27)
				)
				(hide yes)
			)
		)
		(property "Datasheet" ""
			(at 287.02 92.71 0)
			(effects
				(font
					(size 1.27 1.27)
				)
				(hide yes)
			)
		)
		(property "Description" ""
			(at 287.02 92.71 0)
			(effects
				(font
					(size 1.27 1.27)
				)
				(hide yes)
			)
		)
		(property "Author" "Antmicro"
			(at 278.13 100.33 0)
			(effects
				(font
					(size 1.27 1.27)
					(thickness 0.15)
				)
				(justify left bottom)
				(hide yes)
			)
		)
		(property "License" "Apache-2.0"
			(at 278.13 102.87 0)
			(effects
				(font
					(size 1.27 1.27)
					(thickness 0.15)
				)
				(justify left bottom)
				(hide yes)
			)
		)
		(pin "1"
		)
		(instances
			(project "cm4-baseboard"
				(path ""
					(reference "#PWR0721")
					(unit 1)
				)
			)
		)
	)
	(symbol
		(lib_id "antmicroTVSDiodes:PUSB3F96X_PASS")
		(at 123.19 179.07 0)
		(mirror y)
		(unit 1)
		(exclude_from_sim no)
		(in_bom yes)
		(on_board yes)
		(dnp no)
		(fields_autoplaced yes)
		(property "Reference" "D702"
			(at 109.22 181.6099 0)
			(effects
				(font
					(size 1.27 1.27)
					(thickness 0.15)
				)
				(justify left)
			)
		)
		(property "Value" "PUSB3F96X_PASS"
			(at 97.79 186.69 0)
			(effects
				(font
					(size 1.27 1.27)
					(thickness 0.15)
				)
				(justify left bottom)
				(hide yes)
			)
		)
		(property "Footprint" "antmicro-footprints:Nexperia_DFN-10_2.5x1mm_P0.5mm"
			(at 97.79 189.23 0)
			(effects
				(font
					(size 1.27 1.27)
					(thickness 0.15)
				)
				(justify left bottom)
				(hide yes)
			)
		)
		(property "Datasheet" "https://mouser.com/datasheet/2/916/PUSB3F96-1600324.pdf"
			(at 97.79 191.77 0)
			(effects
				(font
					(size 1.27 1.27)
					(thickness 0.15)
				)
				(justify left bottom)
				(hide yes)
			)
		)
		(property "Description" ""
			(at 123.19 179.07 0)
			(effects
				(font
					(size 1.27 1.27)
				)
				(hide yes)
			)
		)
		(property "Manufacturer" "Nexperia"
			(at 97.79 194.31 0)
			(effects
				(font
					(size 1.27 1.27)
					(thickness 0.15)
				)
				(justify left bottom)
				(hide yes)
			)
		)
		(property "MPN" "PUSB3F96X"
			(at 109.22 184.1499 0)
			(effects
				(font
					(size 1.27 1.27)
					(thickness 0.15)
				)
				(justify left)
			)
		)
		(property "Author" "Antmicro"
			(at 97.79 196.85 0)
			(effects
				(font
					(size 1.27 1.27)
					(thickness 0.15)
				)
				(justify left bottom)
				(hide yes)
			)
		)
		(property "License" "Apache-2.0"
			(at 97.79 199.39 0)
			(effects
				(font
					(size 1.27 1.27)
					(thickness 0.15)
				)
				(justify left bottom)
				(hide yes)
			)
		)
		(pin "1"
		)
		(pin "10"
		)
		(pin "2"
		)
		(pin "3"
		)
		(pin "4"
		)
		(pin "5"
		)
		(pin "6"
		)
		(pin "7"
		)
		(pin "8"
		)
		(pin "9"
		)
		(instances
			(project "cm4-baseboard"
				(path ""
					(reference "D702")
					(unit 1)
				)
			)
		)
	)
	(symbol
		(lib_id "antmicropower:+3V3")
		(at 290.83 171.45 0)
		(unit 1)
		(exclude_from_sim no)
		(in_bom yes)
		(on_board yes)
		(dnp no)
		(property "Reference" "#PWR0719"
			(at 306.07 171.45 0)
			(effects
				(font
					(size 1.27 1.27)
					(thickness 0.15)
				)
				(justify left bottom)
				(hide yes)
			)
		)
		(property "Value" "+3V3"
			(at 290.83 167.64 0)
			(effects
				(font
					(size 1.27 1.27)
					(thickness 0.15)
				)
			)
		)
		(property "Footprint" ""
			(at 306.07 179.07 0)
			(effects
				(font
					(size 1.27 1.27)
					(thickness 0.15)
				)
				(justify left bottom)
				(hide yes)
			)
		)
		(property "Datasheet" ""
			(at 306.07 181.61 0)
			(effects
				(font
					(size 1.27 1.27)
					(thickness 0.15)
				)
				(justify left bottom)
				(hide yes)
			)
		)
		(property "Description" ""
			(at 290.83 171.45 0)
			(effects
				(font
					(size 1.27 1.27)
				)
				(hide yes)
			)
		)
		(property "Author" "Antmicro"
			(at 306.07 173.99 0)
			(effects
				(font
					(size 1.27 1.27)
					(thickness 0.15)
				)
				(justify left bottom)
				(hide yes)
			)
		)
		(property "License" "Apache-2.0"
			(at 306.07 176.53 0)
			(effects
				(font
					(size 1.27 1.27)
					(thickness 0.15)
				)
				(justify left bottom)
				(hide yes)
			)
		)
		(pin "1"
		)
		(instances
			(project "cm4-baseboard"
				(path ""
					(reference "#PWR0719")
					(unit 1)
				)
			)
		)
	)
	(symbol
		(lib_id "antmicropower:GND")
		(at 234.95 236.22 0)
		(unit 1)
		(exclude_from_sim no)
		(in_bom yes)
		(on_board yes)
		(dnp no)
		(fields_autoplaced yes)
		(property "Reference" "#PWR0711"
			(at 243.84 238.76 0)
			(effects
				(font
					(size 1.27 1.27)
					(thickness 0.15)
				)
				(justify left bottom)
				(hide yes)
			)
		)
		(property "Value" "GND"
			(at 234.95 241.3 0)
			(effects
				(font
					(size 1.27 1.27)
					(thickness 0.15)
				)
			)
		)
		(property "Footprint" ""
			(at 243.84 243.84 0)
			(effects
				(font
					(size 1.27 1.27)
					(thickness 0.15)
				)
				(justify left bottom)
				(hide yes)
			)
		)
		(property "Datasheet" ""
			(at 243.84 248.92 0)
			(effects
				(font
					(size 1.27 1.27)
					(thickness 0.15)
				)
				(justify left bottom)
				(hide yes)
			)
		)
		(property "Description" ""
			(at 234.95 236.22 0)
			(effects
				(font
					(size 1.27 1.27)
				)
				(hide yes)
			)
		)
		(property "Author" "Antmicro"
			(at 243.84 243.84 0)
			(effects
				(font
					(size 1.27 1.27)
					(thickness 0.15)
				)
				(justify left bottom)
				(hide yes)
			)
		)
		(property "License" "Apache-2.0"
			(at 243.84 246.38 0)
			(effects
				(font
					(size 1.27 1.27)
					(thickness 0.15)
				)
				(justify left bottom)
				(hide yes)
			)
		)
		(pin "1"
		)
		(instances
			(project "cm4-baseboard"
				(path ""
					(reference "#PWR0711")
					(unit 1)
				)
			)
		)
	)
	(symbol
		(lib_id "antmicroTVSDiodes:PUSB3F96X_PASS")
		(at 123.19 241.3 0)
		(mirror y)
		(unit 1)
		(exclude_from_sim no)
		(in_bom yes)
		(on_board yes)
		(dnp no)
		(fields_autoplaced yes)
		(property "Reference" "D705"
			(at 109.22 243.8399 0)
			(effects
				(font
					(size 1.27 1.27)
					(thickness 0.15)
				)
				(justify left)
			)
		)
		(property "Value" "PUSB3F96X_PASS"
			(at 97.79 248.92 0)
			(effects
				(font
					(size 1.27 1.27)
					(thickness 0.15)
				)
				(justify left bottom)
				(hide yes)
			)
		)
		(property "Footprint" "antmicro-footprints:Nexperia_DFN-10_2.5x1mm_P0.5mm"
			(at 97.79 251.46 0)
			(effects
				(font
					(size 1.27 1.27)
					(thickness 0.15)
				)
				(justify left bottom)
				(hide yes)
			)
		)
		(property "Datasheet" "https://mouser.com/datasheet/2/916/PUSB3F96-1600324.pdf"
			(at 97.79 254 0)
			(effects
				(font
					(size 1.27 1.27)
					(thickness 0.15)
				)
				(justify left bottom)
				(hide yes)
			)
		)
		(property "Description" ""
			(at 123.19 241.3 0)
			(effects
				(font
					(size 1.27 1.27)
				)
				(hide yes)
			)
		)
		(property "Manufacturer" "Nexperia"
			(at 97.79 256.54 0)
			(effects
				(font
					(size 1.27 1.27)
					(thickness 0.15)
				)
				(justify left bottom)
				(hide yes)
			)
		)
		(property "MPN" "PUSB3F96X"
			(at 109.22 246.3799 0)
			(effects
				(font
					(size 1.27 1.27)
					(thickness 0.15)
				)
				(justify left)
			)
		)
		(property "Author" "Antmicro"
			(at 97.79 259.08 0)
			(effects
				(font
					(size 1.27 1.27)
					(thickness 0.15)
				)
				(justify left bottom)
				(hide yes)
			)
		)
		(property "License" "Apache-2.0"
			(at 97.79 261.62 0)
			(effects
				(font
					(size 1.27 1.27)
					(thickness 0.15)
				)
				(justify left bottom)
				(hide yes)
			)
		)
		(pin "1"
		)
		(pin "10"
		)
		(pin "2"
		)
		(pin "3"
		)
		(pin "4"
		)
		(pin "5"
		)
		(pin "6"
		)
		(pin "7"
		)
		(pin "8"
		)
		(pin "9"
		)
		(instances
			(project "cm4-baseboard"
				(path ""
					(reference "D705")
					(unit 1)
				)
			)
		)
	)
	(symbol
		(lib_id "antmicroFerriteBeadsandChips:FB_220Z_2.2A_TDK-MPZ_0603")
		(at 226.06 91.44 0)
		(unit 1)
		(exclude_from_sim no)
		(in_bom yes)
		(on_board yes)
		(dnp no)
		(fields_autoplaced yes)
		(property "Reference" "FB701"
			(at 228.5619 95.25 0)
			(effects
				(font
					(size 1.27 1.27)
				)
			)
		)
		(property "Value" "FB_220Z_2.2A_TDK-MPZ_0603"
			(at 220.98 88.9 0)
			(effects
				(font
					(size 1.27 1.27)
					(thickness 0.15)
				)
				(justify left bottom)
				(hide yes)
			)
		)
		(property "Footprint" "antmicro-footprints:FB_0603_1608Metric"
			(at 240.03 96.52 0)
			(effects
				(font
					(size 1.27 1.27)
					(thickness 0.15)
				)
				(justify left bottom)
				(hide yes)
			)
		)
		(property "Datasheet" "https://product.tdk.com/info/en/catalog/datasheets/beads_commercial_power_mpz1608_en.pdf"
			(at 240.03 99.06 0)
			(effects
				(font
					(size 1.27 1.27)
					(thickness 0.15)
				)
				(justify left bottom)
				(hide yes)
			)
		)
		(property "Description" ""
			(at 226.06 91.44 0)
			(effects
				(font
					(size 1.27 1.27)
				)
				(hide yes)
			)
		)
		(property "MPN" "MPZ1608S221ATA00"
			(at 218.44 100.33 0)
			(effects
				(font
					(size 1.27 1.27)
					(thickness 0.15)
				)
				(justify left bottom)
				(hide yes)
			)
		)
		(property "Manufacturer" "TDK"
			(at 240.03 104.14 0)
			(effects
				(font
					(size 1.27 1.27)
					(thickness 0.15)
				)
				(justify left bottom)
				(hide yes)
			)
		)
		(property "Author" "Antmicro"
			(at 240.03 106.68 0)
			(effects
				(font
					(size 1.27 1.27)
					(thickness 0.15)
				)
				(justify left bottom)
				(hide yes)
			)
		)
		(property "License" "Apache-2.0"
			(at 240.03 109.22 0)
			(effects
				(font
					(size 1.27 1.27)
					(thickness 0.15)
				)
				(justify left bottom)
				(hide yes)
			)
		)
		(property "Val" "220Z/2.2A"
			(at 228.5619 97.79 0)
			(effects
				(font
					(size 1.27 1.27)
				)
			)
		)
		(property "Current" ""
			(at 246.38 114.3 0)
			(effects
				(font
					(size 1.27 1.27)
					(thickness 0.15)
				)
				(justify left bottom)
				(hide yes)
			)
		)
		(pin "1"
		)
		(pin "2"
		)
		(instances
			(project "cm4-baseboard"
				(path ""
					(reference "FB701")
					(unit 1)
				)
			)
		)
	)
	(symbol
		(lib_id "antmicroCapacitors0402:C_10u_0402")
		(at 285.75 177.8 270)
		(mirror x)
		(unit 1)
		(exclude_from_sim no)
		(in_bom yes)
		(on_board yes)
		(dnp no)
		(property "Reference" "C703"
			(at 284.48 173.99 90)
			(effects
				(font
					(size 1.27 1.27)
					(thickness 0.15)
				)
				(justify right)
			)
		)
		(property "Value" "C_10u_0402"
			(at 275.59 157.48 0)
			(effects
				(font
					(size 1.27 1.27)
					(thickness 0.15)
				)
				(justify left bottom)
				(hide yes)
			)
		)
		(property "Footprint" "antmicro-footprints:C_0402_1005Metric"
			(at 273.05 157.48 0)
			(effects
				(font
					(size 1.27 1.27)
					(thickness 0.15)
				)
				(justify left bottom)
				(hide yes)
			)
		)
		(property "Datasheet" "https://www.yageo.com/en/Chart/Download/pdf/CC0402MRX5R5BB106"
			(at 270.51 157.48 0)
			(effects
				(font
					(size 1.27 1.27)
					(thickness 0.15)
				)
				(justify left bottom)
				(hide yes)
			)
		)
		(property "Description" ""
			(at 285.75 177.8 0)
			(effects
				(font
					(size 1.27 1.27)
				)
				(hide yes)
			)
		)
		(property "MPN" "CC0402MRX5R5BB106"
			(at 267.97 157.48 0)
			(effects
				(font
					(size 1.27 1.27)
					(thickness 0.15)
				)
				(justify left bottom)
				(hide yes)
			)
		)
		(property "Manufacturer" "YAGEO"
			(at 265.43 157.48 0)
			(effects
				(font
					(size 1.27 1.27)
					(thickness 0.15)
				)
				(justify left bottom)
				(hide yes)
			)
		)
		(property "License" "Apache-2.0"
			(at 262.89 157.48 0)
			(effects
				(font
					(size 1.27 1.27)
					(thickness 0.15)
				)
				(justify left bottom)
				(hide yes)
			)
		)
		(property "Author" "Antmicro"
			(at 260.35 157.48 0)
			(effects
				(font
					(size 1.27 1.27)
					(thickness 0.15)
				)
				(justify left bottom)
				(hide yes)
			)
		)
		(property "Val" "10u"
			(at 284.48 176.53 90)
			(effects
				(font
					(size 1.27 1.27)
					(thickness 0.15)
				)
				(justify right)
			)
		)
		(property "Voltage" ""
			(at 257.81 157.48 0)
			(effects
				(font
					(size 1.27 1.27)
				)
				(justify left bottom)
				(hide yes)
			)
		)
		(property "Dielectric" ""
			(at 255.27 157.48 0)
			(effects
				(font
					(size 1.27 1.27)
				)
				(justify left bottom)
				(hide yes)
			)
		)
		(pin "1"
		)
		(pin "2"
		)
		(instances
			(project "cm4-baseboard"
				(path ""
					(reference "C703")
					(unit 1)
				)
			)
		)
	)
	(symbol
		(lib_id "antmicroResistorNetworksArrays:R_4x100R_0402_array")
		(at 238.76 73.66 0)
		(unit 1)
		(exclude_from_sim no)
		(in_bom yes)
		(on_board yes)
		(dnp no)
		(fields_autoplaced yes)
		(property "Reference" "R701"
			(at 243.84 67.31 0)
			(effects
				(font
					(size 1.27 1.27)
					(thickness 0.15)
				)
			)
		)
		(property "Value" "R_4x100R_0402_array"
			(at 259.08 86.36 0)
			(effects
				(font
					(size 1.27 1.27)
					(thickness 0.15)
				)
				(justify left bottom)
				(hide yes)
			)
		)
		(property "Footprint" "antmicro-footprints:R_Array_4x0402_Panasonic_EXB28V"
			(at 259.08 88.9 0)
			(effects
				(font
					(size 1.27 1.27)
					(thickness 0.15)
				)
				(justify left bottom)
				(hide yes)
			)
		)
		(property "Datasheet" "http://industrial.panasonic.com/cdbs/www-data/pdf/AOC0000/AOC0000C14.pdf"
			(at 259.08 91.44 0)
			(effects
				(font
					(size 1.27 1.27)
					(thickness 0.15)
				)
				(justify left bottom)
				(hide yes)
			)
		)
		(property "Description" ""
			(at 238.76 73.66 0)
			(effects
				(font
					(size 1.27 1.27)
				)
				(hide yes)
			)
		)
		(property "MPN" "EXB-28V101JX"
			(at 259.08 93.98 0)
			(effects
				(font
					(size 1.27 1.27)
					(thickness 0.15)
				)
				(justify left bottom)
				(hide yes)
			)
		)
		(property "Manufacturer" "Panasonic"
			(at 259.08 96.52 0)
			(effects
				(font
					(size 1.27 1.27)
					(thickness 0.15)
				)
				(justify left bottom)
				(hide yes)
			)
		)
		(property "License" "Apache-2.0"
			(at 259.08 99.06 0)
			(effects
				(font
					(size 1.27 1.27)
					(thickness 0.15)
				)
				(justify left bottom)
				(hide yes)
			)
		)
		(property "Author" "Antmicro"
			(at 259.08 101.6 0)
			(effects
				(font
					(size 1.27 1.27)
					(thickness 0.15)
				)
				(justify left bottom)
				(hide yes)
			)
		)
		(property "Val" "R_4x100R_0402"
			(at 243.84 69.85 0)
			(effects
				(font
					(size 1.27 1.27)
					(thickness 0.15)
				)
			)
		)
		(pin "1"
		)
		(pin "2"
		)
		(pin "8"
		)
		(pin "6"
		)
		(pin "3"
		)
		(pin "4"
		)
		(pin "5"
		)
		(pin "7"
		)
		(instances
			(project "cm4-baseboard"
				(path ""
					(reference "R701")
					(unit 1)
				)
			)
		)
	)
	(symbol
		(lib_id "antmicroTVSDiodes:PUSB3F96X_PASS")
		(at 123.19 198.12 0)
		(mirror y)
		(unit 1)
		(exclude_from_sim no)
		(in_bom yes)
		(on_board yes)
		(dnp no)
		(fields_autoplaced yes)
		(property "Reference" "D703"
			(at 109.22 200.6599 0)
			(effects
				(font
					(size 1.27 1.27)
					(thickness 0.15)
				)
				(justify left)
			)
		)
		(property "Value" "PUSB3F96X_PASS"
			(at 97.79 205.74 0)
			(effects
				(font
					(size 1.27 1.27)
					(thickness 0.15)
				)
				(justify left bottom)
				(hide yes)
			)
		)
		(property "Footprint" "antmicro-footprints:Nexperia_DFN-10_2.5x1mm_P0.5mm"
			(at 97.79 208.28 0)
			(effects
				(font
					(size 1.27 1.27)
					(thickness 0.15)
				)
				(justify left bottom)
				(hide yes)
			)
		)
		(property "Datasheet" "https://mouser.com/datasheet/2/916/PUSB3F96-1600324.pdf"
			(at 97.79 210.82 0)
			(effects
				(font
					(size 1.27 1.27)
					(thickness 0.15)
				)
				(justify left bottom)
				(hide yes)
			)
		)
		(property "Description" ""
			(at 123.19 198.12 0)
			(effects
				(font
					(size 1.27 1.27)
				)
				(hide yes)
			)
		)
		(property "Manufacturer" "Nexperia"
			(at 97.79 213.36 0)
			(effects
				(font
					(size 1.27 1.27)
					(thickness 0.15)
				)
				(justify left bottom)
				(hide yes)
			)
		)
		(property "MPN" "PUSB3F96X"
			(at 109.22 203.1999 0)
			(effects
				(font
					(size 1.27 1.27)
					(thickness 0.15)
				)
				(justify left)
			)
		)
		(property "Author" "Antmicro"
			(at 97.79 215.9 0)
			(effects
				(font
					(size 1.27 1.27)
					(thickness 0.15)
				)
				(justify left bottom)
				(hide yes)
			)
		)
		(property "License" "Apache-2.0"
			(at 97.79 218.44 0)
			(effects
				(font
					(size 1.27 1.27)
					(thickness 0.15)
				)
				(justify left bottom)
				(hide yes)
			)
		)
		(pin "1"
		)
		(pin "10"
		)
		(pin "2"
		)
		(pin "3"
		)
		(pin "4"
		)
		(pin "5"
		)
		(pin "6"
		)
		(pin "7"
		)
		(pin "8"
		)
		(pin "9"
		)
		(instances
			(project "cm4-baseboard"
				(path ""
					(reference "D703")
					(unit 1)
				)
			)
		)
	)
	(symbol
		(lib_id "antmicroMechanicalParts:Spacer_Drill3.7mm_H2mm_9774020151R")
		(at 246.38 256.54 0)
		(mirror y)
		(unit 1)
		(exclude_from_sim no)
		(in_bom yes)
		(on_board yes)
		(dnp no)
		(fields_autoplaced yes)
		(property "Reference" "H701"
			(at 241.3 248.92 0)
			(effects
				(font
					(size 1.27 1.27)
					(thickness 0.15)
				)
			)
		)
		(property "Value" "Spacer_Drill3.7mm_H2mm_9774020151R"
			(at 241.3 251.46 0)
			(effects
				(font
					(size 1.27 1.27)
					(thickness 0.15)
				)
			)
		)
		(property "Footprint" "antmicro-footprints:Spacer_Drill3.7mm_H2mm_9774020151R"
			(at 223.52 264.16 0)
			(effects
				(font
					(size 1.27 1.27)
					(thickness 0.15)
				)
				(justify left bottom)
				(hide yes)
			)
		)
		(property "Datasheet" "https://www.we-online.com/components/products/datasheet/9774020151R.pdf"
			(at 223.52 266.7 0)
			(effects
				(font
					(size 1.27 1.27)
					(thickness 0.15)
				)
				(justify left bottom)
				(hide yes)
			)
		)
		(property "Description" ""
			(at 246.38 256.54 0)
			(effects
				(font
					(size 1.27 1.27)
				)
				(hide yes)
			)
		)
		(property "Manufacturer" "Würth Elektronik"
			(at 223.52 269.24 0)
			(effects
				(font
					(size 1.27 1.27)
					(thickness 0.15)
				)
				(justify left bottom)
				(hide yes)
			)
		)
		(property "MPN" "9774020151R"
			(at 241.3 251.46 0)
			(effects
				(font
					(size 1.27 1.27)
					(thickness 0.15)
				)
				(hide yes)
			)
		)
		(property "Author" "Antmicro"
			(at 223.52 274.32 0)
			(effects
				(font
					(size 1.27 1.27)
					(thickness 0.15)
				)
				(justify left bottom)
				(hide yes)
			)
		)
		(property "License" "Apache-2.0"
			(at 223.52 276.86 0)
			(effects
				(font
					(size 1.27 1.27)
					(thickness 0.15)
				)
				(justify left bottom)
				(hide yes)
			)
		)
		(pin "1"
		)
		(instances
			(project "cm4-baseboard"
				(path ""
					(reference "H701")
					(unit 1)
				)
			)
		)
	)
	(symbol
		(lib_id "antmicropower:+3V3")
		(at 242.57 194.31 0)
		(unit 1)
		(exclude_from_sim no)
		(in_bom yes)
		(on_board yes)
		(dnp no)
		(property "Reference" "#PWR0714"
			(at 257.81 194.31 0)
			(effects
				(font
					(size 1.27 1.27)
					(thickness 0.15)
				)
				(justify left bottom)
				(hide yes)
			)
		)
		(property "Value" "+3V3"
			(at 242.57 190.5 0)
			(effects
				(font
					(size 1.27 1.27)
					(thickness 0.15)
				)
			)
		)
		(property "Footprint" ""
			(at 257.81 201.93 0)
			(effects
				(font
					(size 1.27 1.27)
					(thickness 0.15)
				)
				(justify left bottom)
				(hide yes)
			)
		)
		(property "Datasheet" ""
			(at 257.81 204.47 0)
			(effects
				(font
					(size 1.27 1.27)
					(thickness 0.15)
				)
				(justify left bottom)
				(hide yes)
			)
		)
		(property "Description" ""
			(at 242.57 194.31 0)
			(effects
				(font
					(size 1.27 1.27)
				)
				(hide yes)
			)
		)
		(property "Author" "Antmicro"
			(at 257.81 196.85 0)
			(effects
				(font
					(size 1.27 1.27)
					(thickness 0.15)
				)
				(justify left bottom)
				(hide yes)
			)
		)
		(property "License" "Apache-2.0"
			(at 257.81 199.39 0)
			(effects
				(font
					(size 1.27 1.27)
					(thickness 0.15)
				)
				(justify left bottom)
				(hide yes)
			)
		)
		(pin "1"
		)
		(instances
			(project "cm4-baseboard"
				(path ""
					(reference "#PWR0714")
					(unit 1)
				)
			)
		)
	)
	(symbol
		(lib_id "antmicroTVSDiodes:PESD5Z5_0F")
		(at 238.76 175.26 90)
		(mirror x)
		(unit 1)
		(exclude_from_sim no)
		(in_bom yes)
		(on_board yes)
		(dnp no)
		(property "Reference" "D709"
			(at 240.03 176.53 90)
			(effects
				(font
					(size 1.27 1.27)
					(thickness 0.15)
				)
				(justify right)
			)
		)
		(property "Value" "PESD5Z5_0F"
			(at 241.3 178.1175 90)
			(effects
				(font
					(size 1.27 1.27)
					(thickness 0.15)
				)
				(justify right)
				(hide yes)
			)
		)
		(property "Footprint" "antmicro-footprints:SOD-523"
			(at 243.84 190.5 0)
			(effects
				(font
					(size 1.27 1.27)
					(thickness 0.15)
				)
				(justify left bottom)
				(hide yes)
			)
		)
		(property "Datasheet" "https://assets.nexperia.com/documents/data-sheet/PESD5Z5_0.pdf"
			(at 246.38 190.5 0)
			(effects
				(font
					(size 1.27 1.27)
					(thickness 0.15)
				)
				(justify left bottom)
				(hide yes)
			)
		)
		(property "Description" ""
			(at 238.76 175.26 0)
			(effects
				(font
					(size 1.27 1.27)
				)
				(hide yes)
			)
		)
		(property "Manufacturer" "Nexperia"
			(at 248.92 190.5 0)
			(effects
				(font
					(size 1.27 1.27)
					(thickness 0.15)
				)
				(justify left bottom)
				(hide yes)
			)
		)
		(property "MPN" "PESD5Z5.0F"
			(at 240.03 179.07 90)
			(effects
				(font
					(size 1.27 1.27)
					(thickness 0.15)
				)
				(justify right)
			)
		)
		(property "Author" "Antmicro"
			(at 254 190.5 0)
			(effects
				(font
					(size 1.27 1.27)
					(thickness 0.15)
				)
				(justify left bottom)
				(hide yes)
			)
		)
		(property "License" "Apache-2.0"
			(at 256.54 190.5 0)
			(effects
				(font
					(size 1.27 1.27)
					(thickness 0.15)
				)
				(justify left bottom)
				(hide yes)
			)
		)
		(pin "2"
		)
		(pin "1"
		)
		(instances
			(project "cm4-baseboard"
				(path ""
					(reference "D709")
					(unit 1)
				)
			)
		)
	)
	(symbol
		(lib_id "antmicropower:GND")
		(at 124.46 190.5 0)
		(mirror y)
		(unit 1)
		(exclude_from_sim no)
		(in_bom yes)
		(on_board yes)
		(dnp no)
		(fields_autoplaced yes)
		(property "Reference" "#PWR0702"
			(at 115.57 193.04 0)
			(effects
				(font
					(size 1.27 1.27)
					(thickness 0.15)
				)
				(justify left bottom)
				(hide yes)
			)
		)
		(property "Value" "GND"
			(at 124.46 195.58 0)
			(effects
				(font
					(size 1.27 1.27)
				)
			)
		)
		(property "Footprint" ""
			(at 115.57 198.12 0)
			(effects
				(font
					(size 1.27 1.27)
					(thickness 0.15)
				)
				(justify left bottom)
				(hide yes)
			)
		)
		(property "Datasheet" ""
			(at 115.57 203.2 0)
			(effects
				(font
					(size 1.27 1.27)
					(thickness 0.15)
				)
				(justify left bottom)
				(hide yes)
			)
		)
		(property "Description" ""
			(at 124.46 190.5 0)
			(effects
				(font
					(size 1.27 1.27)
				)
				(hide yes)
			)
		)
		(property "Author" "Antmicro"
			(at 115.57 198.12 0)
			(effects
				(font
					(size 1.27 1.27)
					(thickness 0.15)
				)
				(justify left bottom)
				(hide yes)
			)
		)
		(property "License" "Apache-2.0"
			(at 115.57 200.66 0)
			(effects
				(font
					(size 1.27 1.27)
					(thickness 0.15)
				)
				(justify left bottom)
				(hide yes)
			)
		)
		(pin "1"
		)
		(instances
			(project "cm4-baseboard"
				(path ""
					(reference "#PWR0702")
					(unit 1)
				)
			)
		)
	)
	(symbol
		(lib_id "antmicropower:+5V")
		(at 218.44 90.17 0)
		(unit 1)
		(exclude_from_sim no)
		(in_bom yes)
		(on_board yes)
		(dnp no)
		(property "Reference" "#PWR0710"
			(at 218.44 93.98 0)
			(effects
				(font
					(size 1.27 1.27)
				)
				(justify left bottom)
				(hide yes)
			)
		)
		(property "Value" "+5V"
			(at 217.17 86.36 0)
			(effects
				(font
					(size 1.27 1.27)
				)
			)
		)
		(property "Footprint" ""
			(at 218.44 90.17 0)
			(effects
				(font
					(size 1.27 1.27)
				)
				(hide yes)
			)
		)
		(property "Datasheet" ""
			(at 218.44 90.17 0)
			(effects
				(font
					(size 1.27 1.27)
				)
				(hide yes)
			)
		)
		(property "Description" ""
			(at 218.44 90.17 0)
			(effects
				(font
					(size 1.27 1.27)
				)
				(hide yes)
			)
		)
		(property "Author" "Antmicro"
			(at 233.68 97.79 0)
			(effects
				(font
					(size 1.27 1.27)
					(thickness 0.15)
				)
				(justify left bottom)
				(hide yes)
			)
		)
		(property "License" "Apache-2.0"
			(at 233.68 100.33 0)
			(effects
				(font
					(size 1.27 1.27)
					(thickness 0.15)
				)
				(justify left bottom)
				(hide yes)
			)
		)
		(pin "1"
		)
		(instances
			(project "cm4-baseboard"
				(path ""
					(reference "#PWR0710")
					(unit 1)
				)
			)
		)
	)
	(symbol
		(lib_id "antmicroFerriteBeadsandChips:FB_220Z_2.2A_TDK-MPZ_0603")
		(at 270.51 172.72 0)
		(mirror y)
		(unit 1)
		(exclude_from_sim no)
		(in_bom yes)
		(on_board yes)
		(dnp no)
		(fields_autoplaced yes)
		(property "Reference" "FB702"
			(at 268.0081 176.53 0)
			(effects
				(font
					(size 1.27 1.27)
				)
			)
		)
		(property "Value" "FB_220Z_2.2A_TDK-MPZ_0603"
			(at 275.59 170.18 0)
			(effects
				(font
					(size 1.27 1.27)
					(thickness 0.15)
				)
				(justify left bottom)
				(hide yes)
			)
		)
		(property "Footprint" "antmicro-footprints:FB_0603_1608Metric"
			(at 256.54 177.8 0)
			(effects
				(font
					(size 1.27 1.27)
					(thickness 0.15)
				)
				(justify left bottom)
				(hide yes)
			)
		)
		(property "Datasheet" "https://product.tdk.com/info/en/catalog/datasheets/beads_commercial_power_mpz1608_en.pdf"
			(at 256.54 180.34 0)
			(effects
				(font
					(size 1.27 1.27)
					(thickness 0.15)
				)
				(justify left bottom)
				(hide yes)
			)
		)
		(property "Description" ""
			(at 270.51 172.72 0)
			(effects
				(font
					(size 1.27 1.27)
				)
				(hide yes)
			)
		)
		(property "MPN" "MPZ1608S221ATA00"
			(at 278.13 181.61 0)
			(effects
				(font
					(size 1.27 1.27)
					(thickness 0.15)
				)
				(justify left bottom)
				(hide yes)
			)
		)
		(property "Manufacturer" "TDK"
			(at 256.54 185.42 0)
			(effects
				(font
					(size 1.27 1.27)
					(thickness 0.15)
				)
				(justify left bottom)
				(hide yes)
			)
		)
		(property "Author" "Antmicro"
			(at 256.54 187.96 0)
			(effects
				(font
					(size 1.27 1.27)
					(thickness 0.15)
				)
				(justify left bottom)
				(hide yes)
			)
		)
		(property "License" "Apache-2.0"
			(at 256.54 190.5 0)
			(effects
				(font
					(size 1.27 1.27)
					(thickness 0.15)
				)
				(justify left bottom)
				(hide yes)
			)
		)
		(property "Val" "220Z/2.2A"
			(at 268.0081 179.07 0)
			(effects
				(font
					(size 1.27 1.27)
				)
			)
		)
		(property "Current" ""
			(at 250.19 195.58 0)
			(effects
				(font
					(size 1.27 1.27)
					(thickness 0.15)
				)
				(justify left bottom)
				(hide yes)
			)
		)
		(pin "1"
		)
		(pin "2"
		)
		(instances
			(project "cm4-baseboard"
				(path ""
					(reference "FB702")
					(unit 1)
				)
			)
		)
	)
	(symbol
		(lib_id "antmicroResistorNetworksArrays:R_4x100R_0402_array")
		(at 243.84 200.66 0)
		(unit 1)
		(exclude_from_sim no)
		(in_bom yes)
		(on_board yes)
		(dnp no)
		(property "Reference" "R705"
			(at 248.92 194.31 0)
			(effects
				(font
					(size 1.27 1.27)
					(thickness 0.15)
				)
			)
		)
		(property "Value" "R_4x100R_0402_array"
			(at 270.51 205.74 0)
			(effects
				(font
					(size 1.27 1.27)
					(thickness 0.15)
				)
				(justify left bottom)
				(hide yes)
			)
		)
		(property "Footprint" "antmicro-footprints:R_Array_4x0402_Panasonic_EXB28V"
			(at 270.51 210.82 0)
			(effects
				(font
					(size 1.27 1.27)
					(thickness 0.15)
				)
				(justify left bottom)
				(hide yes)
			)
		)
		(property "Datasheet" "http://industrial.panasonic.com/cdbs/www-data/pdf/AOC0000/AOC0000C14.pdf"
			(at 270.51 213.36 0)
			(effects
				(font
					(size 1.27 1.27)
					(thickness 0.15)
				)
				(justify left bottom)
				(hide yes)
			)
		)
		(property "Description" ""
			(at 243.84 200.66 0)
			(effects
				(font
					(size 1.27 1.27)
				)
				(hide yes)
			)
		)
		(property "MPN" "EXB-28V101JX"
			(at 270.51 215.9 0)
			(effects
				(font
					(size 1.27 1.27)
					(thickness 0.15)
				)
				(justify left bottom)
				(hide yes)
			)
		)
		(property "Manufacturer" "Panasonic"
			(at 270.51 218.44 0)
			(effects
				(font
					(size 1.27 1.27)
					(thickness 0.15)
				)
				(justify left bottom)
				(hide yes)
			)
		)
		(property "Author" "Antmicro"
			(at 270.51 220.98 0)
			(effects
				(font
					(size 1.27 1.27)
					(thickness 0.15)
				)
				(justify left bottom)
				(hide yes)
			)
		)
		(property "License" "Apache-2.0"
			(at 270.51 223.52 0)
			(effects
				(font
					(size 1.27 1.27)
					(thickness 0.15)
				)
				(justify left bottom)
				(hide yes)
			)
		)
		(property "Val" "R_4x100R_0402"
			(at 248.92 196.85 0)
			(effects
				(font
					(size 1.27 1.27)
				)
			)
		)
		(pin "8"
		)
		(pin "4"
		)
		(pin "6"
		)
		(pin "3"
		)
		(pin "5"
		)
		(pin "7"
		)
		(pin "2"
		)
		(pin "1"
		)
		(instances
			(project "cm4-baseboard"
				(path ""
					(reference "R705")
					(unit 1)
				)
			)
		)
	)
	(symbol
		(lib_id "antmicroCapacitors0402:C_10u_0402")
		(at 245.11 100.33 90)
		(unit 1)
		(exclude_from_sim no)
		(in_bom yes)
		(on_board yes)
		(dnp no)
		(fields_autoplaced yes)
		(property "Reference" "C702"
			(at 247.65 96.5135 90)
			(effects
				(font
					(size 1.27 1.27)
					(thickness 0.15)
				)
				(justify right)
			)
		)
		(property "Value" "C_10u_0402"
			(at 255.27 80.01 0)
			(effects
				(font
					(size 1.27 1.27)
					(thickness 0.15)
				)
				(justify left bottom)
				(hide yes)
			)
		)
		(property "Footprint" "antmicro-footprints:C_0402_1005Metric"
			(at 257.81 80.01 0)
			(effects
				(font
					(size 1.27 1.27)
					(thickness 0.15)
				)
				(justify left bottom)
				(hide yes)
			)
		)
		(property "Datasheet" "https://www.yageo.com/en/Chart/Download/pdf/CC0402MRX5R5BB106"
			(at 260.35 80.01 0)
			(effects
				(font
					(size 1.27 1.27)
					(thickness 0.15)
				)
				(justify left bottom)
				(hide yes)
			)
		)
		(property "Description" ""
			(at 245.11 100.33 0)
			(effects
				(font
					(size 1.27 1.27)
				)
				(hide yes)
			)
		)
		(property "MPN" "CC0402MRX5R5BB106"
			(at 262.89 80.01 0)
			(effects
				(font
					(size 1.27 1.27)
					(thickness 0.15)
				)
				(justify left bottom)
				(hide yes)
			)
		)
		(property "Manufacturer" "YAGEO"
			(at 265.43 80.01 0)
			(effects
				(font
					(size 1.27 1.27)
					(thickness 0.15)
				)
				(justify left bottom)
				(hide yes)
			)
		)
		(property "License" "Apache-2.0"
			(at 267.97 80.01 0)
			(effects
				(font
					(size 1.27 1.27)
					(thickness 0.15)
				)
				(justify left bottom)
				(hide yes)
			)
		)
		(property "Author" "Antmicro"
			(at 270.51 80.01 0)
			(effects
				(font
					(size 1.27 1.27)
					(thickness 0.15)
				)
				(justify left bottom)
				(hide yes)
			)
		)
		(property "Val" "10u"
			(at 247.65 99.0535 90)
			(effects
				(font
					(size 1.27 1.27)
					(thickness 0.15)
				)
				(justify right)
			)
		)
		(property "Voltage" ""
			(at 273.05 80.01 0)
			(effects
				(font
					(size 1.27 1.27)
				)
				(justify left bottom)
				(hide yes)
			)
		)
		(property "Dielectric" ""
			(at 275.59 80.01 0)
			(effects
				(font
					(size 1.27 1.27)
				)
				(justify left bottom)
				(hide yes)
			)
		)
		(pin "1"
		)
		(pin "2"
		)
		(instances
			(project "cm4-baseboard"
				(path ""
					(reference "C702")
					(unit 1)
				)
			)
		)
	)
	(symbol
		(lib_id "antmicropower:PWR_FLAG")
		(at 252.73 90.17 0)
		(unit 1)
		(exclude_from_sim no)
		(in_bom yes)
		(on_board yes)
		(dnp no)
		(property "Reference" "#FLG016"
			(at 252.73 88.265 0)
			(effects
				(font
					(size 1.27 1.27)
				)
				(hide yes)
			)
		)
		(property "Value" "PWR_FLAG"
			(at 252.73 86.36 0)
			(effects
				(font
					(size 1.27 1.27)
				)
			)
		)
		(property "Footprint" ""
			(at 252.73 90.17 0)
			(effects
				(font
					(size 1.27 1.27)
				)
				(hide yes)
			)
		)
		(property "Datasheet" ""
			(at 252.73 90.17 0)
			(effects
				(font
					(size 1.27 1.27)
				)
				(hide yes)
			)
		)
		(property "Description" ""
			(at 252.73 90.17 0)
			(effects
				(font
					(size 1.27 1.27)
				)
				(hide yes)
			)
		)
		(pin "1"
		)
		(instances
			(project "cm4-baseboard"
				(path ""
					(reference "#FLG016")
					(unit 1)
				)
			)
		)
	)
	(symbol
		(lib_id "antmicroVideoConnectors:HDMI-A_WE_685119134923")
		(at 260.35 40.64 0)
		(unit 1)
		(exclude_from_sim no)
		(in_bom yes)
		(on_board yes)
		(dnp no)
		(fields_autoplaced yes)
		(property "Reference" "J702"
			(at 273.05 33.02 0)
			(effects
				(font
					(size 1.27 1.27)
					(thickness 0.15)
				)
			)
		)
		(property "Value" "HDMI-A_WE_685119134923"
			(at 273.05 35.56 0)
			(effects
				(font
					(size 1.27 1.27)
					(thickness 0.15)
				)
				(hide yes)
			)
		)
		(property "Footprint" "antmicro-footprints:HDMI-A_Receptacle_WE_685119134923"
			(at 295.91 48.26 0)
			(effects
				(font
					(size 1.27 1.27)
					(thickness 0.15)
				)
				(justify left bottom)
				(hide yes)
			)
		)
		(property "Datasheet" "https://www.we-online.com/components/products/datasheet/685119134923.pdf"
			(at 295.91 50.8 0)
			(effects
				(font
					(size 1.27 1.27)
					(thickness 0.15)
				)
				(justify left bottom)
				(hide yes)
			)
		)
		(property "Description" ""
			(at 260.35 40.64 0)
			(effects
				(font
					(size 1.27 1.27)
				)
				(hide yes)
			)
		)
		(property "MPN" "685119134923"
			(at 273.05 35.56 0)
			(effects
				(font
					(size 1.27 1.27)
					(thickness 0.15)
				)
			)
		)
		(property "Manufacturer" "Würth Elektronik"
			(at 295.91 55.88 0)
			(effects
				(font
					(size 1.27 1.27)
					(thickness 0.15)
				)
				(justify left bottom)
				(hide yes)
			)
		)
		(property "Author" "Antmicro"
			(at 295.91 58.42 0)
			(effects
				(font
					(size 1.27 1.27)
					(thickness 0.15)
				)
				(justify left bottom)
				(hide yes)
			)
		)
		(property "License" "Apache-2.0"
			(at 295.91 60.96 0)
			(effects
				(font
					(size 1.27 1.27)
					(thickness 0.15)
				)
				(justify left bottom)
				(hide yes)
			)
		)
		(pin "1"
		)
		(pin "10"
		)
		(pin "11"
		)
		(pin "12"
		)
		(pin "13"
		)
		(pin "14"
		)
		(pin "15"
		)
		(pin "16"
		)
		(pin "17"
		)
		(pin "18"
		)
		(pin "19"
		)
		(pin "2"
		)
		(pin "3"
		)
		(pin "4"
		)
		(pin "5"
		)
		(pin "6"
		)
		(pin "7"
		)
		(pin "8"
		)
		(pin "9"
		)
		(pin "SH"
		)
		(instances
			(project "cm4-baseboard"
				(path ""
					(reference "J702")
					(unit 1)
				)
			)
		)
	)
	(symbol
		(lib_id "antmicropower:GND")
		(at 124.46 233.68 0)
		(mirror y)
		(unit 1)
		(exclude_from_sim no)
		(in_bom yes)
		(on_board yes)
		(dnp no)
		(fields_autoplaced yes)
		(property "Reference" "#PWR0704"
			(at 115.57 236.22 0)
			(effects
				(font
					(size 1.27 1.27)
					(thickness 0.15)
				)
				(justify left bottom)
				(hide yes)
			)
		)
		(property "Value" "GND"
			(at 124.46 238.76 0)
			(effects
				(font
					(size 1.27 1.27)
				)
			)
		)
		(property "Footprint" ""
			(at 115.57 241.3 0)
			(effects
				(font
					(size 1.27 1.27)
					(thickness 0.15)
				)
				(justify left bottom)
				(hide yes)
			)
		)
		(property "Datasheet" ""
			(at 115.57 246.38 0)
			(effects
				(font
					(size 1.27 1.27)
					(thickness 0.15)
				)
				(justify left bottom)
				(hide yes)
			)
		)
		(property "Description" ""
			(at 124.46 233.68 0)
			(effects
				(font
					(size 1.27 1.27)
				)
				(hide yes)
			)
		)
		(property "Author" "Antmicro"
			(at 115.57 241.3 0)
			(effects
				(font
					(size 1.27 1.27)
					(thickness 0.15)
				)
				(justify left bottom)
				(hide yes)
			)
		)
		(property "License" "Apache-2.0"
			(at 115.57 243.84 0)
			(effects
				(font
					(size 1.27 1.27)
					(thickness 0.15)
				)
				(justify left bottom)
				(hide yes)
			)
		)
		(pin "1"
		)
		(instances
			(project "cm4-baseboard"
				(path ""
					(reference "#PWR0704")
					(unit 1)
				)
			)
		)
	)
	(symbol
		(lib_id "antmicroTVSDiodes:PUSB3F96X_PASS")
		(at 123.19 222.25 0)
		(mirror y)
		(unit 1)
		(exclude_from_sim no)
		(in_bom yes)
		(on_board yes)
		(dnp no)
		(fields_autoplaced yes)
		(property "Reference" "D704"
			(at 109.22 224.7899 0)
			(effects
				(font
					(size 1.27 1.27)
					(thickness 0.15)
				)
				(justify left)
			)
		)
		(property "Value" "PUSB3F96X_PASS"
			(at 97.79 229.87 0)
			(effects
				(font
					(size 1.27 1.27)
					(thickness 0.15)
				)
				(justify left bottom)
				(hide yes)
			)
		)
		(property "Footprint" "antmicro-footprints:Nexperia_DFN-10_2.5x1mm_P0.5mm"
			(at 97.79 232.41 0)
			(effects
				(font
					(size 1.27 1.27)
					(thickness 0.15)
				)
				(justify left bottom)
				(hide yes)
			)
		)
		(property "Datasheet" "https://mouser.com/datasheet/2/916/PUSB3F96-1600324.pdf"
			(at 97.79 234.95 0)
			(effects
				(font
					(size 1.27 1.27)
					(thickness 0.15)
				)
				(justify left bottom)
				(hide yes)
			)
		)
		(property "Description" ""
			(at 123.19 222.25 0)
			(effects
				(font
					(size 1.27 1.27)
				)
				(hide yes)
			)
		)
		(property "Manufacturer" "Nexperia"
			(at 97.79 237.49 0)
			(effects
				(font
					(size 1.27 1.27)
					(thickness 0.15)
				)
				(justify left bottom)
				(hide yes)
			)
		)
		(property "MPN" "PUSB3F96X"
			(at 109.22 227.3299 0)
			(effects
				(font
					(size 1.27 1.27)
					(thickness 0.15)
				)
				(justify left)
			)
		)
		(property "Author" "Antmicro"
			(at 97.79 240.03 0)
			(effects
				(font
					(size 1.27 1.27)
					(thickness 0.15)
				)
				(justify left bottom)
				(hide yes)
			)
		)
		(property "License" "Apache-2.0"
			(at 97.79 242.57 0)
			(effects
				(font
					(size 1.27 1.27)
					(thickness 0.15)
				)
				(justify left bottom)
				(hide yes)
			)
		)
		(pin "1"
		)
		(pin "10"
		)
		(pin "2"
		)
		(pin "3"
		)
		(pin "4"
		)
		(pin "5"
		)
		(pin "6"
		)
		(pin "7"
		)
		(pin "8"
		)
		(pin "9"
		)
		(instances
			(project "cm4-baseboard"
				(path ""
					(reference "D704")
					(unit 1)
				)
			)
		)
	)
	(symbol
		(lib_id "antmicroTVSDiodes:PUSB3F96X_PASS")
		(at 177.8 58.42 0)
		(unit 1)
		(exclude_from_sim no)
		(in_bom yes)
		(on_board yes)
		(dnp no)
		(fields_autoplaced yes)
		(property "Reference" "D707"
			(at 191.77 62.2299 0)
			(effects
				(font
					(size 1.27 1.27)
					(thickness 0.15)
				)
				(justify left)
			)
		)
		(property "Value" "PUSB3F96X_PASS"
			(at 203.2 66.04 0)
			(effects
				(font
					(size 1.27 1.27)
					(thickness 0.15)
				)
				(justify left bottom)
				(hide yes)
			)
		)
		(property "Footprint" "antmicro-footprints:Nexperia_DFN-10_2.5x1mm_P0.5mm"
			(at 203.2 68.58 0)
			(effects
				(font
					(size 1.27 1.27)
					(thickness 0.15)
				)
				(justify left bottom)
				(hide yes)
			)
		)
		(property "Datasheet" "https://mouser.com/datasheet/2/916/PUSB3F96-1600324.pdf"
			(at 203.2 71.12 0)
			(effects
				(font
					(size 1.27 1.27)
					(thickness 0.15)
				)
				(justify left bottom)
				(hide yes)
			)
		)
		(property "Description" ""
			(at 177.8 58.42 0)
			(effects
				(font
					(size 1.27 1.27)
				)
				(hide yes)
			)
		)
		(property "Manufacturer" "Nexperia"
			(at 203.2 73.66 0)
			(effects
				(font
					(size 1.27 1.27)
					(thickness 0.15)
				)
				(justify left bottom)
				(hide yes)
			)
		)
		(property "MPN" "PUSB3F96X"
			(at 191.77 64.7699 0)
			(effects
				(font
					(size 1.27 1.27)
					(thickness 0.15)
				)
				(justify left)
			)
		)
		(property "Author" "Antmicro"
			(at 203.2 76.2 0)
			(effects
				(font
					(size 1.27 1.27)
					(thickness 0.15)
				)
				(justify left bottom)
				(hide yes)
			)
		)
		(property "License" "Apache-2.0"
			(at 203.2 78.74 0)
			(effects
				(font
					(size 1.27 1.27)
					(thickness 0.15)
				)
				(justify left bottom)
				(hide yes)
			)
		)
		(pin "1"
		)
		(pin "10"
		)
		(pin "2"
		)
		(pin "3"
		)
		(pin "4"
		)
		(pin "5"
		)
		(pin "6"
		)
		(pin "7"
		)
		(pin "8"
		)
		(pin "9"
		)
		(instances
			(project "cm4-baseboard"
				(path ""
					(reference "D707")
					(unit 1)
				)
			)
		)
	)
	(symbol
		(lib_id "antmicroCapacitors0402:C_10u_0402")
		(at 259.08 180.34 270)
		(mirror x)
		(unit 1)
		(exclude_from_sim no)
		(in_bom yes)
		(on_board yes)
		(dnp no)
		(property "Reference" "C701"
			(at 257.81 176.53 90)
			(effects
				(font
					(size 1.27 1.27)
					(thickness 0.15)
				)
				(justify right)
			)
		)
		(property "Value" "C_10u_0402"
			(at 248.92 160.02 0)
			(effects
				(font
					(size 1.27 1.27)
					(thickness 0.15)
				)
				(justify left bottom)
				(hide yes)
			)
		)
		(property "Footprint" "antmicro-footprints:C_0402_1005Metric"
			(at 246.38 160.02 0)
			(effects
				(font
					(size 1.27 1.27)
					(thickness 0.15)
				)
				(justify left bottom)
				(hide yes)
			)
		)
		(property "Datasheet" "https://www.yageo.com/en/Chart/Download/pdf/CC0402MRX5R5BB106"
			(at 243.84 160.02 0)
			(effects
				(font
					(size 1.27 1.27)
					(thickness 0.15)
				)
				(justify left bottom)
				(hide yes)
			)
		)
		(property "Description" ""
			(at 259.08 180.34 0)
			(effects
				(font
					(size 1.27 1.27)
				)
				(hide yes)
			)
		)
		(property "MPN" "CC0402MRX5R5BB106"
			(at 241.3 160.02 0)
			(effects
				(font
					(size 1.27 1.27)
					(thickness 0.15)
				)
				(justify left bottom)
				(hide yes)
			)
		)
		(property "Manufacturer" "YAGEO"
			(at 238.76 160.02 0)
			(effects
				(font
					(size 1.27 1.27)
					(thickness 0.15)
				)
				(justify left bottom)
				(hide yes)
			)
		)
		(property "License" "Apache-2.0"
			(at 236.22 160.02 0)
			(effects
				(font
					(size 1.27 1.27)
					(thickness 0.15)
				)
				(justify left bottom)
				(hide yes)
			)
		)
		(property "Author" "Antmicro"
			(at 233.68 160.02 0)
			(effects
				(font
					(size 1.27 1.27)
					(thickness 0.15)
				)
				(justify left bottom)
				(hide yes)
			)
		)
		(property "Val" "10u"
			(at 257.81 179.07 90)
			(effects
				(font
					(size 1.27 1.27)
					(thickness 0.15)
				)
				(justify right)
			)
		)
		(property "Voltage" ""
			(at 231.14 160.02 0)
			(effects
				(font
					(size 1.27 1.27)
				)
				(justify left bottom)
				(hide yes)
			)
		)
		(property "Dielectric" ""
			(at 228.6 160.02 0)
			(effects
				(font
					(size 1.27 1.27)
				)
				(justify left bottom)
				(hide yes)
			)
		)
		(pin "1"
		)
		(pin "2"
		)
		(instances
			(project "cm4-baseboard"
				(path ""
					(reference "C701")
					(unit 1)
				)
			)
		)
	)
	(symbol
		(lib_id "antmicropower:GND")
		(at 245.11 102.87 0)
		(unit 1)
		(exclude_from_sim no)
		(in_bom yes)
		(on_board yes)
		(dnp no)
		(fields_autoplaced yes)
		(property "Reference" "#PWR0715"
			(at 245.11 109.22 0)
			(effects
				(font
					(size 1.27 1.27)
				)
				(justify left bottom)
				(hide yes)
			)
		)
		(property "Value" "GND"
			(at 245.11 106.68 0)
			(effects
				(font
					(size 1.27 1.27)
				)
			)
		)
		(property "Footprint" ""
			(at 245.11 102.87 0)
			(effects
				(font
					(size 1.27 1.27)
				)
				(hide yes)
			)
		)
		(property "Datasheet" ""
			(at 245.11 102.87 0)
			(effects
				(font
					(size 1.27 1.27)
				)
				(hide yes)
			)
		)
		(property "Description" ""
			(at 245.11 102.87 0)
			(effects
				(font
					(size 1.27 1.27)
				)
				(hide yes)
			)
		)
		(property "Author" "Antmicro"
			(at 254 110.49 0)
			(effects
				(font
					(size 1.27 1.27)
					(thickness 0.15)
				)
				(justify left bottom)
				(hide yes)
			)
		)
		(property "License" "Apache-2.0"
			(at 254 113.03 0)
			(effects
				(font
					(size 1.27 1.27)
					(thickness 0.15)
				)
				(justify left bottom)
				(hide yes)
			)
		)
		(pin "1"
		)
		(instances
			(project "cm4-baseboard"
				(path ""
					(reference "#PWR0715")
					(unit 1)
				)
			)
		)
	)
	(symbol
		(lib_id "antmicropower:GND")
		(at 238.76 181.61 0)
		(mirror y)
		(unit 1)
		(exclude_from_sim no)
		(in_bom yes)
		(on_board yes)
		(dnp no)
		(fields_autoplaced yes)
		(property "Reference" "#PWR0712"
			(at 229.87 184.15 0)
			(effects
				(font
					(size 1.27 1.27)
					(thickness 0.15)
				)
				(justify left bottom)
				(hide yes)
			)
		)
		(property "Value" "GND"
			(at 240.7702 186.69 0)
			(effects
				(font
					(size 1.27 1.27)
					(thickness 0.15)
				)
				(justify left bottom)
			)
		)
		(property "Footprint" ""
			(at 229.87 189.23 0)
			(effects
				(font
					(size 1.27 1.27)
					(thickness 0.15)
				)
				(justify left bottom)
				(hide yes)
			)
		)
		(property "Datasheet" ""
			(at 229.87 194.31 0)
			(effects
				(font
					(size 1.27 1.27)
					(thickness 0.15)
				)
				(justify left bottom)
				(hide yes)
			)
		)
		(property "Description" ""
			(at 238.76 181.61 0)
			(effects
				(font
					(size 1.27 1.27)
				)
				(hide yes)
			)
		)
		(property "Author" "Antmicro"
			(at 229.87 189.23 0)
			(effects
				(font
					(size 1.27 1.27)
					(thickness 0.15)
				)
				(justify left bottom)
				(hide yes)
			)
		)
		(property "License" "Apache-2.0"
			(at 229.87 191.77 0)
			(effects
				(font
					(size 1.27 1.27)
					(thickness 0.15)
				)
				(justify left bottom)
				(hide yes)
			)
		)
		(pin "1"
		)
		(instances
			(project "cm4-baseboard"
				(path ""
					(reference "#PWR0712")
					(unit 1)
				)
			)
		)
	)
	(symbol
		(lib_id "antmicroDiodesRectifiersSingle:RB521S30T1G")
		(at 242.57 91.44 0)
		(mirror y)
		(unit 1)
		(exclude_from_sim no)
		(in_bom yes)
		(on_board yes)
		(dnp no)
		(property "Reference" "D710"
			(at 242.57 86.36 0)
			(effects
				(font
					(size 1.27 1.27)
				)
				(justify left bottom)
			)
		)
		(property "Value" "RB521S30T1G"
			(at 243.84 88.9 0)
			(effects
				(font
					(size 1.27 1.27)
					(thickness 0.15)
				)
				(justify left bottom)
				(hide yes)
			)
		)
		(property "Footprint" "antmicro-footprints:SOD-523"
			(at 219.71 101.6 0)
			(effects
				(font
					(size 1.27 1.27)
					(thickness 0.15)
				)
				(justify left bottom)
				(hide yes)
			)
		)
		(property "Datasheet" "https://www.onsemi.com/pdf/datasheet/rb521s30t1-d.pdf"
			(at 219.71 104.14 0)
			(effects
				(font
					(size 1.27 1.27)
					(thickness 0.15)
				)
				(justify left bottom)
				(hide yes)
			)
		)
		(property "Description" ""
			(at 242.57 91.44 0)
			(effects
				(font
					(size 1.27 1.27)
				)
				(hide yes)
			)
		)
		(property "MPN" "RB521S30T1G"
			(at 246.38 88.9 0)
			(effects
				(font
					(size 1.27 1.27)
					(thickness 0.15)
				)
				(justify left bottom)
			)
		)
		(property "Manufacturer" "ON Semiconductor"
			(at 219.71 109.22 0)
			(effects
				(font
					(size 1.27 1.27)
					(thickness 0.15)
				)
				(justify left bottom)
				(hide yes)
			)
		)
		(property "Author" "Antmicro"
			(at 219.71 111.76 0)
			(effects
				(font
					(size 1.27 1.27)
					(thickness 0.15)
				)
				(justify left bottom)
				(hide yes)
			)
		)
		(property "License" "Apache-2.0"
			(at 219.71 114.3 0)
			(effects
				(font
					(size 1.27 1.27)
					(thickness 0.15)
				)
				(justify left bottom)
				(hide yes)
			)
		)
		(pin "1"
		)
		(pin "2"
		)
		(instances
			(project "cm4-baseboard"
				(path ""
					(reference "D710")
					(unit 1)
				)
			)
		)
	)
)
